FILE_TYPE = MACRO_DRAWING;
SET COLOR_WIRE YELLOW;
SET COLOR_PROP ORANGE;
SET COLOR_DOT WHITE;
SET COLOR_ARC YELLOW;
SET COLOR_BODY GREEN;
SET COLOR_NOTE PURPLE;
SET PROP_DISPLAY VALUE;
SET PAGE_NUMBER P78;
FORCEADD Q_CAP..1
(-4450 -2200);
FORCEPROP 1 LAST PART_NUMBER CH647KMEA04
J 0
(-4400 -2350);
DISPLAY 0.638298 (-4400 -2350);
DISPLAY INVISIBLE (-4400 -2350);
FORCEPROP 1 LAST TOLERANCE 20%
J 0
(-4400 -2250);
DISPLAY 0.638298 (-4400 -2250);
FORCEPROP 1 LAST VOLTAGE 4V
J 0
(-4400 -2200);
DISPLAY 0.638298 (-4400 -2200);
FORCEPROP 1 LAST PACK_TYPE C0805
J 0
(-4400 -2400);
DISPLAY 0.638298 (-4400 -2400);
FORCEPROP 1 LAST VALUE 47UF
J 0
(-4400 -2150);
DISPLAY 0.638298 (-4400 -2150);
FORCEPROP 1 LAST MATERIAL X6S
J 0
(-4400 -2300);
DISPLAY 0.638298 (-4400 -2300);
FORCEPROP 1 LAST $LOCATION C449
J 0
(-4400 -2100);
DISPLAY 0.978723 (-4400 -2100);
FORCEPROP 1 LASTPIN (-4450 -2100) $PN 1
J 0
(-4440 -2120);
DISPLAY 0.787234 (-4440 -2120);
FORCEPROP 1 LASTPIN (-4450 -2300) $PN 2
J 0
(-4440 -2320);
DISPLAY 0.787234 (-4440 -2320);
FORCEPROP 2 LAST CDS_LIB pure_quanta
J 0
(-4450 -2200);
PAINT MONO (-4450 -2200);
DISPLAY INVISIBLE (-4450 -2200);
FORCEPROP 2 LAST CDS_LOCATION C449
J 0
(-4400 -2000);
DISPLAY 1.021277 (-4400 -2000);
DISPLAY INVISIBLE (-4400 -2000);
FORCEPROP 2 LAST $SEC 1
J 0
(-4400 -2000);
DISPLAY 0.680851 (-4400 -2000);
PAINT MONO (-4400 -2000);
DISPLAY INVISIBLE (-4400 -2000);
FORCEPROP 2 LAST CDS_SEC 1
J 0
(-4400 -2000);
DISPLAY 1.021277 (-4400 -2000);
DISPLAY INVISIBLE (-4400 -2000);
FORCEPROP 1 LAST PATH I1
J 0
(-4400 -2050);
DISPLAY 0.978723 (-4400 -2050);
PAINT WHITE (-4400 -2050);
DISPLAY INVISIBLE (-4400 -2050);
FORCEADD Q_CAP..1
(-4450 -225);
FORCEPROP 1 LAST PART_NUMBER CH647KMEA04
J 0
(-4400 -375);
DISPLAY 0.638298 (-4400 -375);
DISPLAY INVISIBLE (-4400 -375);
FORCEPROP 1 LAST TOLERANCE 20%
J 0
(-4400 -275);
DISPLAY 0.638298 (-4400 -275);
FORCEPROP 1 LAST VOLTAGE 4V
J 0
(-4400 -225);
DISPLAY 0.638298 (-4400 -225);
FORCEPROP 1 LAST PACK_TYPE C0805
J 0
(-4400 -425);
DISPLAY 0.638298 (-4400 -425);
FORCEPROP 1 LAST VALUE 47UF
J 0
(-4400 -175);
DISPLAY 0.638298 (-4400 -175);
FORCEPROP 1 LAST MATERIAL X6S
J 0
(-4400 -325);
DISPLAY 0.638298 (-4400 -325);
FORCEPROP 1 LAST $LOCATION C448
J 0
(-4400 -125);
DISPLAY 0.978723 (-4400 -125);
FORCEPROP 1 LASTPIN (-4450 -125) $PN 1
J 0
(-4440 -145);
DISPLAY 0.787234 (-4440 -145);
FORCEPROP 1 LASTPIN (-4450 -325) $PN 2
J 0
(-4440 -345);
DISPLAY 0.787234 (-4440 -345);
FORCEPROP 2 LAST CDS_LIB pure_quanta
J 0
(-4450 -225);
PAINT MONO (-4450 -225);
DISPLAY INVISIBLE (-4450 -225);
FORCEPROP 2 LAST CDS_LOCATION C448
J 0
(-4400 -25);
DISPLAY 1.021277 (-4400 -25);
DISPLAY INVISIBLE (-4400 -25);
FORCEPROP 2 LAST $SEC 1
J 0
(-4400 -25);
DISPLAY 0.680851 (-4400 -25);
PAINT MONO (-4400 -25);
DISPLAY INVISIBLE (-4400 -25);
FORCEPROP 2 LAST CDS_SEC 1
J 0
(-4400 -25);
DISPLAY 1.021277 (-4400 -25);
DISPLAY INVISIBLE (-4400 -25);
FORCEPROP 1 LAST PATH I10
J 0
(-4400 -75);
DISPLAY 0.978723 (-4400 -75);
PAINT WHITE (-4400 -75);
DISPLAY INVISIBLE (-4400 -75);
FORCEADD UNIVERSAL_POWER..1
(-4450 50);
FORCEPROP 3 LASTPIN (-4450 0) SIG_NAME PVCCFA_EHV_CPU1\g
J 0
(-4440 10);
DISPLAY 0.659574 (-4440 10);
PAINT MONO (-4440 10);
DISPLAY INVISIBLE (-4440 10);
FORCEPROP 1 LAST HDL_POWER PVCCFA_EHV_CPU1
J 1
(-4175 100);
DISPLAY 0.872340 (-4175 100);
PAINT GREEN (-4175 100);
FORCEPROP 2 LAST CDS_LIB logical_power
J 0
(-4450 50);
PAINT MONO (-4450 50);
DISPLAY INVISIBLE (-4450 50);
FORCEPROP 1 LAST PATH I11
J 0
(-4400 75);
DISPLAY 0.872340 (-4400 75);
PAINT AQUA (-4400 75);
DISPLAY INVISIBLE (-4400 75);
FORCEADD Q_CAP..1
(-4450 675);
FORCEPROP 1 LAST PART_NUMBER CH647KMEA04
J 0
(-4400 525);
DISPLAY 0.638298 (-4400 525);
DISPLAY INVISIBLE (-4400 525);
FORCEPROP 1 LAST TOLERANCE 20%
J 0
(-4400 625);
DISPLAY 0.638298 (-4400 625);
FORCEPROP 1 LAST VOLTAGE 4V
J 0
(-4400 675);
DISPLAY 0.638298 (-4400 675);
FORCEPROP 1 LAST VALUE 47UF
J 0
(-4400 725);
DISPLAY 0.638298 (-4400 725);
FORCEPROP 1 LAST MATERIAL X6S
J 0
(-4400 575);
DISPLAY 0.638298 (-4400 575);
FORCEPROP 1 LAST PACK_TYPE C0805
J 0
(-4400 475);
DISPLAY 0.638298 (-4400 475);
FORCEPROP 1 LAST $LOCATION C447
J 0
(-4400 775);
DISPLAY 0.978723 (-4400 775);
FORCEPROP 1 LASTPIN (-4450 775) $PN 1
J 0
(-4440 755);
DISPLAY 0.787234 (-4440 755);
FORCEPROP 1 LASTPIN (-4450 575) $PN 2
J 0
(-4440 555);
DISPLAY 0.787234 (-4440 555);
FORCEPROP 2 LAST CDS_LIB pure_quanta
J 0
(-4450 675);
PAINT MONO (-4450 675);
DISPLAY INVISIBLE (-4450 675);
FORCEPROP 2 LAST CDS_LOCATION C447
J 0
(-4400 875);
DISPLAY 1.021277 (-4400 875);
DISPLAY INVISIBLE (-4400 875);
FORCEPROP 2 LAST $SEC 1
J 0
(-4400 875);
DISPLAY 0.680851 (-4400 875);
PAINT MONO (-4400 875);
DISPLAY INVISIBLE (-4400 875);
FORCEPROP 2 LAST CDS_SEC 1
J 0
(-4400 875);
DISPLAY 1.021277 (-4400 875);
DISPLAY INVISIBLE (-4400 875);
FORCEPROP 1 LAST PATH I12
J 0
(-4400 825);
DISPLAY 0.978723 (-4400 825);
PAINT WHITE (-4400 825);
DISPLAY INVISIBLE (-4400 825);
FORCEADD UNIVERSAL_POWER..1
(-4450 950);
FORCEPROP 3 LASTPIN (-4450 900) SIG_NAME PVCCD_HV_CPU1\g
J 0
(-4440 910);
DISPLAY 0.659574 (-4440 910);
PAINT MONO (-4440 910);
DISPLAY INVISIBLE (-4440 910);
FORCEPROP 1 LAST HDL_POWER PVCCD_HV_CPU1
J 1
(-4225 1000);
DISPLAY 0.872340 (-4225 1000);
PAINT GREEN (-4225 1000);
FORCEPROP 2 LAST CDS_LIB logical_power
J 0
(-4450 950);
PAINT MONO (-4450 950);
DISPLAY INVISIBLE (-4450 950);
FORCEPROP 1 LAST PATH I13
J 0
(-4400 975);
DISPLAY 0.872340 (-4400 975);
PAINT AQUA (-4400 975);
DISPLAY INVISIBLE (-4400 975);
FORCEADD Q_CAP..1
(-4450 1625);
FORCEPROP 1 LAST PART_NUMBER CH647KMEA04
J 0
(-4400 1475);
DISPLAY 0.638298 (-4400 1475);
DISPLAY INVISIBLE (-4400 1475);
FORCEPROP 1 LAST VALUE 47UF
J 0
(-4400 1675);
DISPLAY 0.638298 (-4400 1675);
FORCEPROP 1 LAST TOLERANCE 20%
J 0
(-4400 1575);
DISPLAY 0.638298 (-4400 1575);
FORCEPROP 1 LAST VOLTAGE 4V
J 0
(-4400 1625);
DISPLAY 0.638298 (-4400 1625);
FORCEPROP 1 LAST PACK_TYPE C0805
J 0
(-4400 1425);
DISPLAY 0.638298 (-4400 1425);
FORCEPROP 1 LAST MATERIAL X6S
J 0
(-4400 1525);
DISPLAY 0.638298 (-4400 1525);
FORCEPROP 1 LAST $LOCATION C312
J 0
(-4400 1725);
DISPLAY 0.638298 (-4400 1725);
FORCEPROP 1 LASTPIN (-4450 1725) $PN 1
J 0
(-4440 1705);
DISPLAY 0.787234 (-4440 1705);
FORCEPROP 1 LASTPIN (-4450 1525) $PN 2
J 0
(-4440 1505);
DISPLAY 0.787234 (-4440 1505);
FORCEPROP 2 LAST CDS_LIB pure_quanta
J 0
(-4450 1625);
PAINT MONO (-4450 1625);
DISPLAY INVISIBLE (-4450 1625);
FORCEPROP 1 LAST $LOCATION C312
J 0
(-4400 1825);
DISPLAY 1.021277 (-4400 1825);
DISPLAY INVISIBLE (-4400 1825);
FORCEPROP 2 LAST CDS_LOCATION C312
J 0
(-4400 1825);
DISPLAY 1.021277 (-4400 1825);
DISPLAY INVISIBLE (-4400 1825);
FORCEPROP 2 LAST $SEC 1
J 0
(-4400 1825);
DISPLAY 0.680851 (-4400 1825);
PAINT MONO (-4400 1825);
DISPLAY INVISIBLE (-4400 1825);
FORCEPROP 2 LAST CDS_SEC 1
J 0
(-4400 1825);
DISPLAY 1.021277 (-4400 1825);
DISPLAY INVISIBLE (-4400 1825);
FORCEPROP 1 LAST PATH I14
J 0
(-4400 1775);
DISPLAY 0.978723 (-4400 1775);
PAINT WHITE (-4400 1775);
DISPLAY INVISIBLE (-4400 1775);
FORCEADD UNIVERSAL_POWER..1
(-4450 1900);
FORCEPROP 3 LASTPIN (-4450 1850) SIG_NAME PVCCIN_CPU1\g
J 0
(-4440 1860);
DISPLAY 0.659574 (-4440 1860);
PAINT MONO (-4440 1860);
DISPLAY INVISIBLE (-4440 1860);
FORCEPROP 1 LAST HDL_POWER PVCCIN_CPU1
J 1
(-4250 1950);
DISPLAY 0.872340 (-4250 1950);
PAINT GREEN (-4250 1950);
FORCEPROP 2 LAST CDS_LIB logical_power
J 0
(-4450 1900);
DISPLAY INVISIBLE (-4450 1900);
FORCEPROP 1 LAST PATH I15
J 0
(-4400 1925);
DISPLAY 0.872340 (-4400 1925);
PAINT AQUA (-4400 1925);
DISPLAY INVISIBLE (-4400 1925);
FORCEADD Q_CAP..1
(-4450 2400);
FORCEPROP 1 LAST PART_NUMBER CH647KMEA04
J 0
(-4400 2250);
DISPLAY 0.638298 (-4400 2250);
DISPLAY INVISIBLE (-4400 2250);
FORCEPROP 1 LAST TOLERANCE 20%
J 0
(-4400 2350);
DISPLAY 0.638298 (-4400 2350);
FORCEPROP 1 LAST VOLTAGE 4V
J 0
(-4400 2400);
DISPLAY 0.638298 (-4400 2400);
FORCEPROP 1 LAST PACK_TYPE C0805
J 0
(-4400 2200);
DISPLAY 0.638298 (-4400 2200);
FORCEPROP 1 LAST VALUE 47UF
J 0
(-4400 2450);
DISPLAY 0.638298 (-4400 2450);
FORCEPROP 1 LAST MATERIAL X6S
J 0
(-4400 2300);
DISPLAY 0.638298 (-4400 2300);
FORCEPROP 1 LAST $LOCATION C311
J 0
(-4400 2500);
DISPLAY 0.638298 (-4400 2500);
FORCEPROP 1 LASTPIN (-4450 2500) $PN 1
J 0
(-4440 2480);
DISPLAY 0.787234 (-4440 2480);
FORCEPROP 1 LASTPIN (-4450 2300) $PN 2
J 0
(-4440 2280);
DISPLAY 0.787234 (-4440 2280);
FORCEPROP 2 LAST CDS_LIB pure_quanta
J 0
(-4450 2400);
PAINT MONO (-4450 2400);
DISPLAY INVISIBLE (-4450 2400);
FORCEPROP 1 LAST $LOCATION C311
J 0
(-4400 2600);
DISPLAY 1.021277 (-4400 2600);
DISPLAY INVISIBLE (-4400 2600);
FORCEPROP 2 LAST CDS_LOCATION C311
J 0
(-4400 2600);
DISPLAY 1.021277 (-4400 2600);
DISPLAY INVISIBLE (-4400 2600);
FORCEPROP 2 LAST $SEC 1
J 0
(-4400 2600);
DISPLAY 0.680851 (-4400 2600);
PAINT MONO (-4400 2600);
DISPLAY INVISIBLE (-4400 2600);
FORCEPROP 2 LAST CDS_SEC 1
J 0
(-4400 2600);
DISPLAY 1.021277 (-4400 2600);
DISPLAY INVISIBLE (-4400 2600);
FORCEPROP 1 LAST PATH I16
J 0
(-4400 2550);
DISPLAY 0.978723 (-4400 2550);
PAINT WHITE (-4400 2550);
DISPLAY INVISIBLE (-4400 2550);
FORCEADD UNIVERSAL_POWER..1
(-4450 2675);
FORCEPROP 3 LASTPIN (-4450 2625) SIG_NAME PVCCIN_CPU1\g
J 0
(-4440 2635);
DISPLAY 0.659574 (-4440 2635);
PAINT MONO (-4440 2635);
DISPLAY INVISIBLE (-4440 2635);
FORCEPROP 1 LAST HDL_POWER PVCCIN_CPU1
J 1
(-4250 2725);
DISPLAY 0.872340 (-4250 2725);
PAINT GREEN (-4250 2725);
FORCEPROP 2 LAST CDS_LIB logical_power
J 0
(-4450 2675);
DISPLAY INVISIBLE (-4450 2675);
FORCEPROP 1 LAST PATH I17
J 0
(-4400 2700);
DISPLAY 0.872340 (-4400 2700);
PAINT AQUA (-4400 2700);
DISPLAY INVISIBLE (-4400 2700);
FORCEADD Q_CAP..1
(-4000 -1250);
FORCEPROP 1 LAST PART_NUMBER CH647LME900
J 0
(-3950 -1400);
DISPLAY 0.638298 (-3950 -1400);
DISPLAY INVISIBLE (-3950 -1400);
FORCEPROP 1 LAST TOLERANCE 20%
J 0
(-3950 -1300);
DISPLAY 0.638298 (-3950 -1300);
FORCEPROP 1 LAST VOLTAGE 2.5V
J 0
(-3950 -1250);
DISPLAY 0.638298 (-3950 -1250);
FORCEPROP 1 LAST MATERIAL X6S
J 0
(-3950 -1350);
DISPLAY 0.638298 (-3950 -1350);
FORCEPROP 1 LAST PACK_TYPE C0603
J 0
(-3950 -1450);
DISPLAY 0.638298 (-3950 -1450);
FORCEPROP 1 LAST VALUE 47UF
J 0
(-3950 -1200);
DISPLAY 0.638298 (-3950 -1200);
FORCEPROP 1 LAST $LOCATION C488
J 0
(-3950 -1150);
DISPLAY 0.978723 (-3950 -1150);
FORCEPROP 1 LASTPIN (-4000 -1150) $PN 1
J 0
(-3990 -1170);
DISPLAY 0.787234 (-3990 -1170);
FORCEPROP 1 LASTPIN (-4000 -1350) $PN 2
J 0
(-3990 -1370);
DISPLAY 0.787234 (-3990 -1370);
FORCEPROP 2 LAST CDS_LIB pure_quanta
J 0
(-4000 -1250);
PAINT MONO (-4000 -1250);
DISPLAY INVISIBLE (-4000 -1250);
FORCEPROP 2 LAST CDS_LOCATION C488
J 0
(-3950 -1050);
DISPLAY 1.021277 (-3950 -1050);
DISPLAY INVISIBLE (-3950 -1050);
FORCEPROP 2 LAST $SEC 1
J 0
(-3950 -1050);
DISPLAY 0.680851 (-3950 -1050);
PAINT MONO (-3950 -1050);
DISPLAY INVISIBLE (-3950 -1050);
FORCEPROP 2 LAST CDS_SEC 1
J 0
(-3950 -1050);
DISPLAY 1.021277 (-3950 -1050);
DISPLAY INVISIBLE (-3950 -1050);
FORCEPROP 1 LAST PATH I18
J 0
(-3950 -1100);
DISPLAY 0.978723 (-3950 -1100);
PAINT WHITE (-3950 -1100);
DISPLAY INVISIBLE (-3950 -1100);
FORCEADD Q_CAP..1
(-3550 -1250);
FORCEPROP 1 LAST PART_NUMBER CH647LME900
J 0
(-3500 -1400);
DISPLAY 0.638298 (-3500 -1400);
DISPLAY INVISIBLE (-3500 -1400);
FORCEPROP 1 LAST TOLERANCE 20%
J 0
(-3500 -1300);
DISPLAY 0.638298 (-3500 -1300);
FORCEPROP 1 LAST VOLTAGE 2.5V
J 0
(-3500 -1250);
DISPLAY 0.638298 (-3500 -1250);
FORCEPROP 1 LAST MATERIAL X6S
J 0
(-3500 -1350);
DISPLAY 0.638298 (-3500 -1350);
FORCEPROP 1 LAST PACK_TYPE C0603
J 0
(-3500 -1450);
DISPLAY 0.638298 (-3500 -1450);
FORCEPROP 1 LAST VALUE 47UF
J 0
(-3500 -1200);
DISPLAY 0.638298 (-3500 -1200);
FORCEPROP 1 LAST $LOCATION C489
J 0
(-3500 -1150);
DISPLAY 0.978723 (-3500 -1150);
FORCEPROP 1 LASTPIN (-3550 -1150) $PN 1
J 0
(-3540 -1170);
DISPLAY 0.787234 (-3540 -1170);
FORCEPROP 1 LASTPIN (-3550 -1350) $PN 2
J 0
(-3540 -1370);
DISPLAY 0.787234 (-3540 -1370);
FORCEPROP 2 LAST CDS_LIB pure_quanta
J 0
(-3550 -1250);
PAINT MONO (-3550 -1250);
DISPLAY INVISIBLE (-3550 -1250);
FORCEPROP 2 LAST CDS_LOCATION C489
J 0
(-3500 -1050);
DISPLAY 1.021277 (-3500 -1050);
DISPLAY INVISIBLE (-3500 -1050);
FORCEPROP 2 LAST $SEC 1
J 0
(-3500 -1050);
DISPLAY 0.680851 (-3500 -1050);
PAINT MONO (-3500 -1050);
DISPLAY INVISIBLE (-3500 -1050);
FORCEPROP 2 LAST CDS_SEC 1
J 0
(-3500 -1050);
DISPLAY 1.021277 (-3500 -1050);
DISPLAY INVISIBLE (-3500 -1050);
FORCEPROP 1 LAST PATH I19
J 0
(-3500 -1100);
DISPLAY 0.978723 (-3500 -1100);
PAINT WHITE (-3500 -1100);
DISPLAY INVISIBLE (-3500 -1100);
FORCEADD UNIVERSAL_POWER..1
(-4450 -1925);
FORCEPROP 3 LASTPIN (-4450 -1975) SIG_NAME PVCCFA_EHV_FIVRA_CPU1\g
J 0
(-4440 -1965);
DISPLAY 0.659574 (-4440 -1965);
PAINT MONO (-4440 -1965);
DISPLAY INVISIBLE (-4440 -1965);
FORCEPROP 1 LAST HDL_POWER PVCCFA_EHV_FIVRA_CPU1
J 1
(-4050 -1875);
DISPLAY 0.872340 (-4050 -1875);
PAINT GREEN (-4050 -1875);
FORCEPROP 2 LAST CDS_LIB logical_power
J 0
(-4450 -1925);
DISPLAY INVISIBLE (-4450 -1925);
FORCEPROP 1 LAST PATH I2
J 0
(-4400 -1900);
DISPLAY 0.872340 (-4400 -1900);
PAINT AQUA (-4400 -1900);
DISPLAY INVISIBLE (-4400 -1900);
FORCEADD UNIVERSAL_GND..1
(-4000 -575);
FORCEPROP 3 LASTPIN (-4000 -525) SIG_NAME GND\g
J 0
(-3990 -515);
DISPLAY 0.659574 (-3990 -515);
PAINT MONO (-3990 -515);
DISPLAY INVISIBLE (-3990 -515);
FORCEPROP 2 LAST CDS_LIB logical_power
J 0
(-4000 -575);
PAINT MONO (-4000 -575);
DISPLAY INVISIBLE (-4000 -575);
FORCEPROP 1 LAST HDL_POWER GND
J 1
(-3975 -650);
DISPLAY 0.872340 (-3975 -650);
PAINT GREEN (-3975 -650);
DISPLAY INVISIBLE (-3975 -650);
FORCEPROP 1 LAST PATH I20
J 0
(-3925 -575);
DISPLAY 0.872340 (-3925 -575);
PAINT AQUA (-3925 -575);
DISPLAY INVISIBLE (-3925 -575);
FORCEADD Q_CAP..1
(-4000 -225);
FORCEPROP 1 LAST PART_NUMBER CH647KMEA04
J 0
(-3950 -375);
DISPLAY 0.638298 (-3950 -375);
DISPLAY INVISIBLE (-3950 -375);
FORCEPROP 1 LAST TOLERANCE 20%
J 0
(-3950 -275);
DISPLAY 0.638298 (-3950 -275);
FORCEPROP 1 LAST VOLTAGE 4V
J 0
(-3950 -225);
DISPLAY 0.638298 (-3950 -225);
FORCEPROP 1 LAST PACK_TYPE C0805
J 0
(-3950 -425);
DISPLAY 0.638298 (-3950 -425);
FORCEPROP 1 LAST VALUE 47UF
J 0
(-3950 -175);
DISPLAY 0.638298 (-3950 -175);
FORCEPROP 1 LAST MATERIAL X6S
J 0
(-3950 -325);
DISPLAY 0.638298 (-3950 -325);
FORCEPROP 1 LAST $LOCATION C452
J 0
(-3950 -125);
DISPLAY 0.978723 (-3950 -125);
FORCEPROP 1 LASTPIN (-4000 -125) $PN 1
J 0
(-3990 -145);
DISPLAY 0.787234 (-3990 -145);
FORCEPROP 1 LASTPIN (-4000 -325) $PN 2
J 0
(-3990 -345);
DISPLAY 0.787234 (-3990 -345);
FORCEPROP 2 LAST CDS_LIB pure_quanta
J 0
(-4000 -225);
PAINT MONO (-4000 -225);
DISPLAY INVISIBLE (-4000 -225);
FORCEPROP 2 LAST CDS_LOCATION C452
J 0
(-3950 -25);
DISPLAY 1.021277 (-3950 -25);
DISPLAY INVISIBLE (-3950 -25);
FORCEPROP 2 LAST $SEC 1
J 0
(-3950 -25);
DISPLAY 0.680851 (-3950 -25);
PAINT MONO (-3950 -25);
DISPLAY INVISIBLE (-3950 -25);
FORCEPROP 2 LAST CDS_SEC 1
J 0
(-3950 -25);
DISPLAY 1.021277 (-3950 -25);
DISPLAY INVISIBLE (-3950 -25);
FORCEPROP 1 LAST PATH I21
J 0
(-3950 -75);
DISPLAY 0.978723 (-3950 -75);
PAINT WHITE (-3950 -75);
DISPLAY INVISIBLE (-3950 -75);
FORCEADD UNIVERSAL_GND..1
(-3100 -1600);
FORCEPROP 3 LASTPIN (-3100 -1550) SIG_NAME GND\g
J 0
(-3090 -1540);
DISPLAY 0.659574 (-3090 -1540);
PAINT MONO (-3090 -1540);
DISPLAY INVISIBLE (-3090 -1540);
FORCEPROP 2 LAST CDS_LIB logical_power
J 0
(-3100 -1600);
PAINT MONO (-3100 -1600);
DISPLAY INVISIBLE (-3100 -1600);
FORCEPROP 1 LAST HDL_POWER GND
J 1
(-3075 -1675);
DISPLAY 0.872340 (-3075 -1675);
PAINT GREEN (-3075 -1675);
DISPLAY INVISIBLE (-3075 -1675);
FORCEPROP 1 LAST PATH I22
J 0
(-3025 -1600);
DISPLAY 0.872340 (-3025 -1600);
PAINT AQUA (-3025 -1600);
DISPLAY INVISIBLE (-3025 -1600);
FORCEADD Q_CAP..1
(-3100 -1250);
FORCEPROP 1 LAST PART_NUMBER CH622KMEB01
J 0
(-3050 -1400);
DISPLAY 0.638298 (-3050 -1400);
DISPLAY INVISIBLE (-3050 -1400);
FORCEPROP 1 LAST VALUE 22UF
J 0
(-3050 -1200);
DISPLAY 0.638298 (-3050 -1200);
FORCEPROP 1 LAST TOLERANCE 20%
J 0
(-3050 -1300);
DISPLAY 0.638298 (-3050 -1300);
FORCEPROP 1 LAST MATERIAL X6S
J 0
(-3050 -1350);
DISPLAY 0.638298 (-3050 -1350);
FORCEPROP 1 LAST VOLTAGE 4V
J 0
(-3050 -1250);
DISPLAY 0.638298 (-3050 -1250);
FORCEPROP 1 LAST PACK_TYPE C0402
J 0
(-3050 -1450);
DISPLAY 0.638298 (-3050 -1450);
FORCEPROP 1 LAST $LOCATION C490
J 0
(-3050 -1150);
DISPLAY 0.978723 (-3050 -1150);
FORCEPROP 1 LASTPIN (-3100 -1150) $PN 1
J 0
(-3090 -1170);
DISPLAY 0.787234 (-3090 -1170);
FORCEPROP 1 LASTPIN (-3100 -1350) $PN 2
J 0
(-3090 -1370);
DISPLAY 0.787234 (-3090 -1370);
FORCEPROP 2 LAST CDS_LIB pure_quanta
J 0
(-3100 -1250);
PAINT MONO (-3100 -1250);
DISPLAY INVISIBLE (-3100 -1250);
FORCEPROP 2 LAST CDS_LOCATION C490
J 0
(-3050 -1050);
DISPLAY 1.021277 (-3050 -1050);
DISPLAY INVISIBLE (-3050 -1050);
FORCEPROP 2 LAST $SEC 1
J 0
(-3050 -1050);
DISPLAY 0.680851 (-3050 -1050);
PAINT MONO (-3050 -1050);
DISPLAY INVISIBLE (-3050 -1050);
FORCEPROP 2 LAST CDS_SEC 1
J 0
(-3050 -1050);
DISPLAY 1.021277 (-3050 -1050);
DISPLAY INVISIBLE (-3050 -1050);
FORCEPROP 1 LAST PATH I23
J 0
(-3050 -1100);
DISPLAY 0.978723 (-3050 -1100);
PAINT WHITE (-3050 -1100);
DISPLAY INVISIBLE (-3050 -1100);
FORCEADD Q_CAP..1
(-4000 675);
FORCEPROP 1 LAST PART_NUMBER CH647KMEA04
J 0
(-3950 525);
DISPLAY 0.638298 (-3950 525);
DISPLAY INVISIBLE (-3950 525);
FORCEPROP 1 LAST TOLERANCE 20%
J 0
(-3950 625);
DISPLAY 0.638298 (-3950 625);
FORCEPROP 1 LAST VOLTAGE 4V
J 0
(-3950 675);
DISPLAY 0.638298 (-3950 675);
FORCEPROP 1 LAST PACK_TYPE C0805
J 0
(-3950 475);
DISPLAY 0.638298 (-3950 475);
FORCEPROP 1 LAST VALUE 47UF
J 0
(-3950 725);
DISPLAY 0.638298 (-3950 725);
FORCEPROP 1 LAST MATERIAL X6S
J 0
(-3950 575);
DISPLAY 0.638298 (-3950 575);
FORCEPROP 1 LAST $LOCATION C451
J 0
(-3950 775);
DISPLAY 0.978723 (-3950 775);
FORCEPROP 1 LASTPIN (-4000 775) $PN 1
J 0
(-3990 755);
DISPLAY 0.787234 (-3990 755);
FORCEPROP 1 LASTPIN (-4000 575) $PN 2
J 0
(-3990 555);
DISPLAY 0.787234 (-3990 555);
FORCEPROP 2 LAST CDS_LIB pure_quanta
J 0
(-4000 675);
PAINT MONO (-4000 675);
DISPLAY INVISIBLE (-4000 675);
FORCEPROP 2 LAST CDS_LOCATION C451
J 0
(-3950 875);
DISPLAY 1.021277 (-3950 875);
DISPLAY INVISIBLE (-3950 875);
FORCEPROP 2 LAST $SEC 1
J 0
(-3950 875);
DISPLAY 0.680851 (-3950 875);
PAINT MONO (-3950 875);
DISPLAY INVISIBLE (-3950 875);
FORCEPROP 2 LAST CDS_SEC 1
J 0
(-3950 875);
DISPLAY 1.021277 (-3950 875);
DISPLAY INVISIBLE (-3950 875);
FORCEPROP 1 LAST PATH I24
J 0
(-3950 825);
DISPLAY 0.978723 (-3950 825);
PAINT WHITE (-3950 825);
DISPLAY INVISIBLE (-3950 825);
FORCEADD Q_CAP..1
(-3550 675);
FORCEPROP 1 LAST PART_NUMBER CH647KMEA04
J 0
(-3500 525);
DISPLAY 0.638298 (-3500 525);
DISPLAY INVISIBLE (-3500 525);
FORCEPROP 1 LAST TOLERANCE 20%
J 0
(-3500 625);
DISPLAY 0.638298 (-3500 625);
FORCEPROP 1 LAST VOLTAGE 4V
J 0
(-3500 675);
DISPLAY 0.638298 (-3500 675);
FORCEPROP 1 LAST PACK_TYPE C0805
J 0
(-3500 475);
DISPLAY 0.638298 (-3500 475);
FORCEPROP 1 LAST VALUE 47UF
J 0
(-3500 725);
DISPLAY 0.638298 (-3500 725);
FORCEPROP 1 LAST MATERIAL X6S
J 0
(-3500 575);
DISPLAY 0.638298 (-3500 575);
FORCEPROP 1 LAST $LOCATION C471
J 0
(-3500 775);
DISPLAY 0.978723 (-3500 775);
FORCEPROP 1 LASTPIN (-3550 775) $PN 1
J 0
(-3540 755);
DISPLAY 0.787234 (-3540 755);
PAINT MONO (-3540 755);
FORCEPROP 1 LASTPIN (-3550 575) $PN 2
J 0
(-3540 555);
DISPLAY 0.787234 (-3540 555);
PAINT MONO (-3540 555);
FORCEPROP 2 LAST CDS_LIB pure_quanta
J 0
(-3550 675);
DISPLAY INVISIBLE (-3550 675);
FORCEPROP 2 LAST CDS_LOCATION C471
J 0
(-3500 875);
DISPLAY 1.021277 (-3500 875);
DISPLAY INVISIBLE (-3500 875);
FORCEPROP 0 LAST $SEC 1
J 0
(-3500 825);
DISPLAY 0.680851 (-3500 825);
PAINT MONO (-3500 825);
DISPLAY INVISIBLE (-3500 825);
FORCEPROP 2 LAST CDS_SEC 1
J 0
(-3500 875);
DISPLAY 1.021277 (-3500 875);
DISPLAY INVISIBLE (-3500 875);
FORCEPROP 1 LAST PATH I25
J 0
(-3500 825);
DISPLAY 0.978723 (-3500 825);
PAINT WHITE (-3500 825);
DISPLAY INVISIBLE (-3500 825);
FORCEADD Q_CAP..1
(-4000 1625);
FORCEPROP 1 LAST PART_NUMBER CH647KMEA04
J 0
(-3950 1475);
DISPLAY 0.638298 (-3950 1475);
DISPLAY INVISIBLE (-3950 1475);
FORCEPROP 1 LAST VALUE 47UF
J 0
(-3950 1675);
DISPLAY 0.638298 (-3950 1675);
FORCEPROP 1 LAST TOLERANCE 20%
J 0
(-3950 1575);
DISPLAY 0.638298 (-3950 1575);
FORCEPROP 1 LAST VOLTAGE 4V
J 0
(-3950 1625);
DISPLAY 0.638298 (-3950 1625);
FORCEPROP 1 LAST PACK_TYPE C0805
J 0
(-3950 1425);
DISPLAY 0.638298 (-3950 1425);
FORCEPROP 1 LAST MATERIAL X6S
J 0
(-3950 1525);
DISPLAY 0.638298 (-3950 1525);
FORCEPROP 1 LAST $LOCATION C315
J 0
(-3950 1725);
DISPLAY 0.638298 (-3950 1725);
FORCEPROP 1 LASTPIN (-4000 1725) $PN 1
J 0
(-3990 1705);
DISPLAY 0.787234 (-3990 1705);
FORCEPROP 1 LASTPIN (-4000 1525) $PN 2
J 0
(-3990 1505);
DISPLAY 0.787234 (-3990 1505);
FORCEPROP 2 LAST CDS_LIB pure_quanta
J 0
(-4000 1625);
PAINT MONO (-4000 1625);
DISPLAY INVISIBLE (-4000 1625);
FORCEPROP 1 LAST $LOCATION C315
J 0
(-3950 1825);
DISPLAY 1.021277 (-3950 1825);
DISPLAY INVISIBLE (-3950 1825);
FORCEPROP 2 LAST CDS_LOCATION C315
J 0
(-3950 1825);
DISPLAY 1.021277 (-3950 1825);
DISPLAY INVISIBLE (-3950 1825);
FORCEPROP 2 LAST $SEC 1
J 0
(-3950 1825);
DISPLAY 0.680851 (-3950 1825);
PAINT MONO (-3950 1825);
DISPLAY INVISIBLE (-3950 1825);
FORCEPROP 2 LAST CDS_SEC 1
J 0
(-3950 1825);
DISPLAY 1.021277 (-3950 1825);
DISPLAY INVISIBLE (-3950 1825);
FORCEPROP 1 LAST PATH I26
J 0
(-3950 1775);
DISPLAY 0.978723 (-3950 1775);
PAINT WHITE (-3950 1775);
DISPLAY INVISIBLE (-3950 1775);
FORCEADD Q_CAP..1
(-3550 1625);
FORCEPROP 1 LAST PART_NUMBER CH647KMEA04
J 0
(-3500 1475);
DISPLAY 0.638298 (-3500 1475);
DISPLAY INVISIBLE (-3500 1475);
FORCEPROP 1 LAST VALUE 47UF
J 0
(-3500 1675);
DISPLAY 0.638298 (-3500 1675);
FORCEPROP 1 LAST TOLERANCE 20%
J 0
(-3500 1575);
DISPLAY 0.638298 (-3500 1575);
FORCEPROP 1 LAST VOLTAGE 4V
J 0
(-3500 1625);
DISPLAY 0.638298 (-3500 1625);
FORCEPROP 1 LAST PACK_TYPE C0805
J 0
(-3500 1425);
DISPLAY 0.638298 (-3500 1425);
FORCEPROP 1 LAST MATERIAL X6S
J 0
(-3500 1525);
DISPLAY 0.638298 (-3500 1525);
FORCEPROP 1 LAST $LOCATION C318
J 0
(-3500 1725);
DISPLAY 0.638298 (-3500 1725);
FORCEPROP 1 LASTPIN (-3550 1725) $PN 1
J 0
(-3540 1705);
DISPLAY 0.787234 (-3540 1705);
FORCEPROP 1 LASTPIN (-3550 1525) $PN 2
J 0
(-3540 1505);
DISPLAY 0.787234 (-3540 1505);
FORCEPROP 2 LAST CDS_LIB pure_quanta
J 0
(-3550 1625);
PAINT MONO (-3550 1625);
DISPLAY INVISIBLE (-3550 1625);
FORCEPROP 1 LAST $LOCATION C318
J 0
(-3500 1825);
DISPLAY 1.021277 (-3500 1825);
DISPLAY INVISIBLE (-3500 1825);
FORCEPROP 2 LAST CDS_LOCATION C318
J 0
(-3500 1825);
DISPLAY 1.021277 (-3500 1825);
DISPLAY INVISIBLE (-3500 1825);
FORCEPROP 2 LAST $SEC 1
J 0
(-3500 1825);
DISPLAY 0.680851 (-3500 1825);
PAINT MONO (-3500 1825);
DISPLAY INVISIBLE (-3500 1825);
FORCEPROP 2 LAST CDS_SEC 1
J 0
(-3500 1825);
DISPLAY 1.021277 (-3500 1825);
DISPLAY INVISIBLE (-3500 1825);
FORCEPROP 1 LAST PATH I27
J 0
(-3500 1775);
DISPLAY 0.978723 (-3500 1775);
PAINT WHITE (-3500 1775);
DISPLAY INVISIBLE (-3500 1775);
FORCEADD UNIVERSAL_GND..1
(-3100 350);
FORCEPROP 3 LASTPIN (-3100 400) SIG_NAME GND\g
J 0
(-3090 410);
DISPLAY 0.659574 (-3090 410);
PAINT MONO (-3090 410);
DISPLAY INVISIBLE (-3090 410);
FORCEPROP 2 LAST CDS_LIB logical_power
J 0
(-3100 350);
PAINT MONO (-3100 350);
DISPLAY INVISIBLE (-3100 350);
FORCEPROP 1 LAST HDL_POWER GND
J 1
(-3075 275);
DISPLAY 0.872340 (-3075 275);
PAINT GREEN (-3075 275);
DISPLAY INVISIBLE (-3075 275);
FORCEPROP 1 LAST PATH I28
J 0
(-3025 350);
DISPLAY 0.872340 (-3025 350);
PAINT AQUA (-3025 350);
DISPLAY INVISIBLE (-3025 350);
FORCEADD Q_CAP..1
(-3100 675);
FORCEPROP 1 LAST PART_NUMBER CH647KMEA04
J 0
(-3050 525);
DISPLAY 0.638298 (-3050 525);
DISPLAY INVISIBLE (-3050 525);
FORCEPROP 1 LAST TOLERANCE 20%
J 0
(-3050 625);
DISPLAY 0.638298 (-3050 625);
FORCEPROP 1 LAST VOLTAGE 4V
J 0
(-3050 675);
DISPLAY 0.638298 (-3050 675);
FORCEPROP 1 LAST PACK_TYPE C0805
J 0
(-3050 475);
DISPLAY 0.638298 (-3050 475);
FORCEPROP 1 LAST VALUE 47UF
J 0
(-3050 725);
DISPLAY 0.638298 (-3050 725);
FORCEPROP 1 LAST MATERIAL X6S
J 0
(-3050 575);
DISPLAY 0.638298 (-3050 575);
FORCEPROP 1 LAST $LOCATION C474
J 0
(-3050 775);
DISPLAY 0.978723 (-3050 775);
FORCEPROP 1 LASTPIN (-3100 775) $PN 1
J 0
(-3090 755);
DISPLAY 0.787234 (-3090 755);
PAINT MONO (-3090 755);
FORCEPROP 1 LASTPIN (-3100 575) $PN 2
J 0
(-3090 555);
DISPLAY 0.787234 (-3090 555);
PAINT MONO (-3090 555);
FORCEPROP 2 LAST CDS_LIB pure_quanta
J 0
(-3100 675);
DISPLAY INVISIBLE (-3100 675);
FORCEPROP 2 LAST CDS_LOCATION C474
J 0
(-3050 875);
DISPLAY 1.021277 (-3050 875);
DISPLAY INVISIBLE (-3050 875);
FORCEPROP 0 LAST $SEC 1
J 0
(-3050 825);
DISPLAY 0.680851 (-3050 825);
PAINT MONO (-3050 825);
DISPLAY INVISIBLE (-3050 825);
FORCEPROP 2 LAST CDS_SEC 1
J 0
(-3050 875);
DISPLAY 1.021277 (-3050 875);
DISPLAY INVISIBLE (-3050 875);
FORCEPROP 1 LAST PATH I29
J 0
(-3050 825);
DISPLAY 0.978723 (-3050 825);
PAINT WHITE (-3050 825);
DISPLAY INVISIBLE (-3050 825);
FORCEADD Q_CAP..1
(-4000 -2200);
FORCEPROP 1 LAST PART_NUMBER CH647KMEA04
J 0
(-3950 -2350);
DISPLAY 0.638298 (-3950 -2350);
DISPLAY INVISIBLE (-3950 -2350);
FORCEPROP 1 LAST TOLERANCE 20%
J 0
(-3950 -2250);
DISPLAY 0.638298 (-3950 -2250);
FORCEPROP 1 LAST VOLTAGE 4V
J 0
(-3950 -2200);
DISPLAY 0.638298 (-3950 -2200);
FORCEPROP 1 LAST PACK_TYPE C0805
J 0
(-3950 -2400);
DISPLAY 0.638298 (-3950 -2400);
FORCEPROP 1 LAST VALUE 47UF
J 0
(-3950 -2150);
DISPLAY 0.638298 (-3950 -2150);
FORCEPROP 1 LAST MATERIAL X6S
J 0
(-3950 -2300);
DISPLAY 0.638298 (-3950 -2300);
FORCEPROP 1 LAST $LOCATION C453
J 0
(-3950 -2100);
DISPLAY 0.978723 (-3950 -2100);
FORCEPROP 1 LASTPIN (-4000 -2100) $PN 1
J 0
(-3990 -2120);
DISPLAY 0.787234 (-3990 -2120);
FORCEPROP 1 LASTPIN (-4000 -2300) $PN 2
J 0
(-3990 -2320);
DISPLAY 0.787234 (-3990 -2320);
FORCEPROP 2 LAST CDS_LIB pure_quanta
J 0
(-4000 -2200);
PAINT MONO (-4000 -2200);
DISPLAY INVISIBLE (-4000 -2200);
FORCEPROP 2 LAST CDS_LOCATION C453
J 0
(-3950 -2000);
DISPLAY 1.021277 (-3950 -2000);
DISPLAY INVISIBLE (-3950 -2000);
FORCEPROP 2 LAST $SEC 1
J 0
(-3950 -2000);
DISPLAY 0.680851 (-3950 -2000);
PAINT MONO (-3950 -2000);
DISPLAY INVISIBLE (-3950 -2000);
FORCEPROP 2 LAST CDS_SEC 1
J 0
(-3950 -2000);
DISPLAY 1.021277 (-3950 -2000);
DISPLAY INVISIBLE (-3950 -2000);
FORCEPROP 1 LAST PATH I3
J 0
(-3950 -2050);
DISPLAY 0.978723 (-3950 -2050);
PAINT WHITE (-3950 -2050);
DISPLAY INVISIBLE (-3950 -2050);
FORCEADD Q_CAP..1
(-3100 1625);
FORCEPROP 1 LAST PART_NUMBER CH647KMEA04
J 0
(-3050 1475);
DISPLAY 0.638298 (-3050 1475);
DISPLAY INVISIBLE (-3050 1475);
FORCEPROP 1 LAST VALUE 47UF
J 0
(-3050 1675);
DISPLAY 0.638298 (-3050 1675);
FORCEPROP 1 LAST TOLERANCE 20%
J 0
(-3050 1575);
DISPLAY 0.638298 (-3050 1575);
FORCEPROP 1 LAST VOLTAGE 4V
J 0
(-3050 1625);
DISPLAY 0.638298 (-3050 1625);
FORCEPROP 1 LAST PACK_TYPE C0805
J 0
(-3050 1425);
DISPLAY 0.638298 (-3050 1425);
FORCEPROP 1 LAST MATERIAL X6S
J 0
(-3050 1525);
DISPLAY 0.638298 (-3050 1525);
FORCEPROP 1 LAST $LOCATION C321
J 0
(-3050 1725);
DISPLAY 0.638298 (-3050 1725);
FORCEPROP 1 LASTPIN (-3100 1725) $PN 1
J 0
(-3090 1705);
DISPLAY 0.787234 (-3090 1705);
FORCEPROP 1 LASTPIN (-3100 1525) $PN 2
J 0
(-3090 1505);
DISPLAY 0.787234 (-3090 1505);
FORCEPROP 2 LAST CDS_LIB pure_quanta
J 0
(-3100 1625);
PAINT MONO (-3100 1625);
DISPLAY INVISIBLE (-3100 1625);
FORCEPROP 1 LAST $LOCATION C321
J 0
(-3050 1825);
DISPLAY 1.021277 (-3050 1825);
DISPLAY INVISIBLE (-3050 1825);
FORCEPROP 2 LAST CDS_LOCATION C321
J 0
(-3050 1825);
DISPLAY 1.021277 (-3050 1825);
DISPLAY INVISIBLE (-3050 1825);
FORCEPROP 2 LAST $SEC 1
J 0
(-3050 1825);
DISPLAY 0.680851 (-3050 1825);
PAINT MONO (-3050 1825);
DISPLAY INVISIBLE (-3050 1825);
FORCEPROP 2 LAST CDS_SEC 1
J 0
(-3050 1825);
DISPLAY 1.021277 (-3050 1825);
DISPLAY INVISIBLE (-3050 1825);
FORCEPROP 1 LAST PATH I30
J 0
(-3050 1775);
DISPLAY 0.978723 (-3050 1775);
PAINT WHITE (-3050 1775);
DISPLAY INVISIBLE (-3050 1775);
FORCEADD Q_CAP..1
(-2650 1625);
FORCEPROP 1 LAST PART_NUMBER CH647KMEA04
J 0
(-2600 1475);
DISPLAY 0.638298 (-2600 1475);
DISPLAY INVISIBLE (-2600 1475);
FORCEPROP 1 LAST VALUE 47UF
J 0
(-2600 1675);
DISPLAY 0.638298 (-2600 1675);
FORCEPROP 1 LAST TOLERANCE 20%
J 0
(-2600 1575);
DISPLAY 0.638298 (-2600 1575);
FORCEPROP 1 LAST VOLTAGE 4V
J 0
(-2600 1625);
DISPLAY 0.638298 (-2600 1625);
FORCEPROP 1 LAST PACK_TYPE C0805
J 0
(-2600 1425);
DISPLAY 0.638298 (-2600 1425);
FORCEPROP 1 LAST MATERIAL X6S
J 0
(-2600 1525);
DISPLAY 0.638298 (-2600 1525);
FORCEPROP 1 LAST $LOCATION C324
J 0
(-2600 1725);
DISPLAY 0.638298 (-2600 1725);
FORCEPROP 1 LASTPIN (-2650 1725) $PN 1
J 0
(-2640 1705);
DISPLAY 0.787234 (-2640 1705);
FORCEPROP 1 LASTPIN (-2650 1525) $PN 2
J 0
(-2640 1505);
DISPLAY 0.787234 (-2640 1505);
FORCEPROP 2 LAST CDS_LIB pure_quanta
J 0
(-2650 1625);
PAINT MONO (-2650 1625);
DISPLAY INVISIBLE (-2650 1625);
FORCEPROP 1 LAST $LOCATION C324
J 0
(-2600 1825);
DISPLAY 1.021277 (-2600 1825);
DISPLAY INVISIBLE (-2600 1825);
FORCEPROP 2 LAST CDS_LOCATION C324
J 0
(-2600 1825);
DISPLAY 1.021277 (-2600 1825);
DISPLAY INVISIBLE (-2600 1825);
FORCEPROP 2 LAST $SEC 1
J 0
(-2600 1825);
DISPLAY 0.680851 (-2600 1825);
PAINT MONO (-2600 1825);
DISPLAY INVISIBLE (-2600 1825);
FORCEPROP 2 LAST CDS_SEC 1
J 0
(-2600 1825);
DISPLAY 1.021277 (-2600 1825);
DISPLAY INVISIBLE (-2600 1825);
FORCEPROP 1 LAST PATH I31
J 0
(-2600 1775);
DISPLAY 0.978723 (-2600 1775);
PAINT WHITE (-2600 1775);
DISPLAY INVISIBLE (-2600 1775);
FORCEADD Q_CAP..1
(-2200 1625);
FORCEPROP 1 LAST PART_NUMBER CH647KMEA04
J 0
(-2150 1475);
DISPLAY 0.638298 (-2150 1475);
DISPLAY INVISIBLE (-2150 1475);
FORCEPROP 1 LAST VALUE 47UF
J 0
(-2150 1675);
DISPLAY 0.638298 (-2150 1675);
FORCEPROP 1 LAST TOLERANCE 20%
J 0
(-2150 1575);
DISPLAY 0.638298 (-2150 1575);
FORCEPROP 1 LAST VOLTAGE 4V
J 0
(-2150 1625);
DISPLAY 0.638298 (-2150 1625);
FORCEPROP 1 LAST PACK_TYPE C0805
J 0
(-2150 1425);
DISPLAY 0.638298 (-2150 1425);
FORCEPROP 1 LAST MATERIAL X6S
J 0
(-2150 1525);
DISPLAY 0.638298 (-2150 1525);
FORCEPROP 1 LAST $LOCATION C327
J 0
(-2150 1725);
DISPLAY 0.638298 (-2150 1725);
FORCEPROP 1 LASTPIN (-2200 1725) $PN 1
J 0
(-2190 1705);
DISPLAY 0.787234 (-2190 1705);
FORCEPROP 1 LASTPIN (-2200 1525) $PN 2
J 0
(-2190 1505);
DISPLAY 0.787234 (-2190 1505);
FORCEPROP 2 LAST CDS_LIB pure_quanta
J 0
(-2200 1625);
PAINT MONO (-2200 1625);
DISPLAY INVISIBLE (-2200 1625);
FORCEPROP 1 LAST $LOCATION C327
J 0
(-2150 1825);
DISPLAY 1.021277 (-2150 1825);
DISPLAY INVISIBLE (-2150 1825);
FORCEPROP 2 LAST CDS_LOCATION C327
J 0
(-2150 1825);
DISPLAY 1.021277 (-2150 1825);
DISPLAY INVISIBLE (-2150 1825);
FORCEPROP 2 LAST $SEC 1
J 0
(-2150 1825);
DISPLAY 0.680851 (-2150 1825);
PAINT MONO (-2150 1825);
DISPLAY INVISIBLE (-2150 1825);
FORCEPROP 2 LAST CDS_SEC 1
J 0
(-2150 1825);
DISPLAY 1.021277 (-2150 1825);
DISPLAY INVISIBLE (-2150 1825);
FORCEPROP 1 LAST PATH I32
J 0
(-2150 1775);
DISPLAY 0.978723 (-2150 1775);
PAINT WHITE (-2150 1775);
DISPLAY INVISIBLE (-2150 1775);
FORCEADD Q_CAP..1
(-1750 1625);
FORCEPROP 1 LAST PART_NUMBER CH647KMEA04
J 0
(-1700 1475);
DISPLAY 0.638298 (-1700 1475);
DISPLAY INVISIBLE (-1700 1475);
FORCEPROP 1 LAST VALUE 47UF
J 0
(-1700 1675);
DISPLAY 0.638298 (-1700 1675);
FORCEPROP 1 LAST TOLERANCE 20%
J 0
(-1700 1575);
DISPLAY 0.638298 (-1700 1575);
FORCEPROP 1 LAST VOLTAGE 4V
J 0
(-1700 1625);
DISPLAY 0.638298 (-1700 1625);
FORCEPROP 1 LAST PACK_TYPE C0805
J 0
(-1700 1425);
DISPLAY 0.638298 (-1700 1425);
FORCEPROP 1 LAST MATERIAL X6S
J 0
(-1700 1525);
DISPLAY 0.638298 (-1700 1525);
FORCEPROP 1 LAST $LOCATION C330
J 0
(-1700 1725);
DISPLAY 0.638298 (-1700 1725);
FORCEPROP 1 LASTPIN (-1750 1725) $PN 1
J 0
(-1740 1705);
DISPLAY 0.787234 (-1740 1705);
FORCEPROP 1 LASTPIN (-1750 1525) $PN 2
J 0
(-1740 1505);
DISPLAY 0.787234 (-1740 1505);
FORCEPROP 2 LAST CDS_LIB pure_quanta
J 0
(-1750 1625);
PAINT MONO (-1750 1625);
DISPLAY INVISIBLE (-1750 1625);
FORCEPROP 1 LAST $LOCATION C330
J 0
(-1700 1825);
DISPLAY 1.021277 (-1700 1825);
DISPLAY INVISIBLE (-1700 1825);
FORCEPROP 2 LAST CDS_LOCATION C330
J 0
(-1700 1825);
DISPLAY 1.021277 (-1700 1825);
DISPLAY INVISIBLE (-1700 1825);
FORCEPROP 2 LAST $SEC 1
J 0
(-1700 1825);
DISPLAY 0.680851 (-1700 1825);
PAINT MONO (-1700 1825);
DISPLAY INVISIBLE (-1700 1825);
FORCEPROP 2 LAST CDS_SEC 1
J 0
(-1700 1825);
DISPLAY 1.021277 (-1700 1825);
DISPLAY INVISIBLE (-1700 1825);
FORCEPROP 1 LAST PATH I33
J 0
(-1700 1775);
DISPLAY 0.978723 (-1700 1775);
PAINT WHITE (-1700 1775);
DISPLAY INVISIBLE (-1700 1775);
FORCEADD Q_CAP..1
(-1300 1625);
FORCEPROP 1 LAST PART_NUMBER CH647KMEA04
J 0
(-1250 1475);
DISPLAY 0.638298 (-1250 1475);
DISPLAY INVISIBLE (-1250 1475);
FORCEPROP 1 LAST TOLERANCE 20%
J 0
(-1250 1575);
DISPLAY 0.638298 (-1250 1575);
FORCEPROP 1 LAST VALUE 47UF
J 0
(-1250 1675);
DISPLAY 0.638298 (-1250 1675);
FORCEPROP 1 LAST VOLTAGE 4V
J 0
(-1250 1625);
DISPLAY 0.638298 (-1250 1625);
FORCEPROP 1 LAST PACK_TYPE C0805
J 0
(-1250 1425);
DISPLAY 0.638298 (-1250 1425);
FORCEPROP 1 LAST MATERIAL X6S
J 0
(-1250 1525);
DISPLAY 0.638298 (-1250 1525);
FORCEPROP 1 LAST $LOCATION C333
J 0
(-1250 1725);
DISPLAY 0.638298 (-1250 1725);
FORCEPROP 1 LASTPIN (-1300 1725) $PN 1
J 0
(-1290 1705);
DISPLAY 0.787234 (-1290 1705);
FORCEPROP 1 LASTPIN (-1300 1525) $PN 2
J 0
(-1290 1505);
DISPLAY 0.787234 (-1290 1505);
FORCEPROP 2 LAST CDS_LIB pure_quanta
J 0
(-1300 1625);
PAINT MONO (-1300 1625);
DISPLAY INVISIBLE (-1300 1625);
FORCEPROP 1 LAST $LOCATION C333
J 0
(-1250 1825);
DISPLAY 1.021277 (-1250 1825);
DISPLAY INVISIBLE (-1250 1825);
FORCEPROP 2 LAST CDS_LOCATION C333
J 0
(-1250 1825);
DISPLAY 1.021277 (-1250 1825);
DISPLAY INVISIBLE (-1250 1825);
FORCEPROP 2 LAST $SEC 1
J 0
(-1250 1825);
DISPLAY 0.680851 (-1250 1825);
PAINT MONO (-1250 1825);
DISPLAY INVISIBLE (-1250 1825);
FORCEPROP 2 LAST CDS_SEC 1
J 0
(-1250 1825);
DISPLAY 1.021277 (-1250 1825);
DISPLAY INVISIBLE (-1250 1825);
FORCEPROP 1 LAST PATH I34
J 0
(-1250 1775);
DISPLAY 0.978723 (-1250 1775);
PAINT WHITE (-1250 1775);
DISPLAY INVISIBLE (-1250 1775);
FORCEADD Q_CAP..1
(-850 1625);
FORCEPROP 1 LAST PART_NUMBER CH647KMEA04
J 0
(-800 1475);
DISPLAY 0.638298 (-800 1475);
DISPLAY INVISIBLE (-800 1475);
FORCEPROP 1 LAST VALUE 47UF
J 0
(-800 1675);
DISPLAY 0.638298 (-800 1675);
FORCEPROP 1 LAST TOLERANCE 20%
J 0
(-800 1575);
DISPLAY 0.638298 (-800 1575);
FORCEPROP 1 LAST VOLTAGE 4V
J 0
(-800 1625);
DISPLAY 0.638298 (-800 1625);
FORCEPROP 1 LAST PACK_TYPE C0805
J 0
(-800 1425);
DISPLAY 0.638298 (-800 1425);
FORCEPROP 1 LAST MATERIAL X6S
J 0
(-800 1525);
DISPLAY 0.638298 (-800 1525);
FORCEPROP 1 LAST $LOCATION C336
J 0
(-800 1725);
DISPLAY 0.638298 (-800 1725);
FORCEPROP 1 LASTPIN (-850 1725) $PN 1
J 0
(-840 1705);
DISPLAY 0.787234 (-840 1705);
FORCEPROP 1 LASTPIN (-850 1525) $PN 2
J 0
(-840 1505);
DISPLAY 0.787234 (-840 1505);
FORCEPROP 2 LAST CDS_LIB pure_quanta
J 0
(-850 1625);
PAINT MONO (-850 1625);
DISPLAY INVISIBLE (-850 1625);
FORCEPROP 1 LAST $LOCATION C336
J 0
(-800 1825);
DISPLAY 1.021277 (-800 1825);
DISPLAY INVISIBLE (-800 1825);
FORCEPROP 2 LAST CDS_LOCATION C336
J 0
(-800 1825);
DISPLAY 1.021277 (-800 1825);
DISPLAY INVISIBLE (-800 1825);
FORCEPROP 2 LAST $SEC 1
J 0
(-800 1825);
DISPLAY 0.680851 (-800 1825);
PAINT MONO (-800 1825);
DISPLAY INVISIBLE (-800 1825);
FORCEPROP 2 LAST CDS_SEC 1
J 0
(-800 1825);
DISPLAY 1.021277 (-800 1825);
DISPLAY INVISIBLE (-800 1825);
FORCEPROP 1 LAST PATH I35
J 0
(-800 1775);
DISPLAY 0.978723 (-800 1775);
PAINT WHITE (-800 1775);
DISPLAY INVISIBLE (-800 1775);
FORCEADD Q_CAP..1
(-400 1625);
FORCEPROP 1 LAST PART_NUMBER CH647KMEA04
J 0
(-350 1475);
DISPLAY 0.638298 (-350 1475);
DISPLAY INVISIBLE (-350 1475);
FORCEPROP 1 LAST VALUE 47UF
J 0
(-350 1675);
DISPLAY 0.638298 (-350 1675);
FORCEPROP 1 LAST TOLERANCE 20%
J 0
(-350 1575);
DISPLAY 0.638298 (-350 1575);
FORCEPROP 1 LAST VOLTAGE 4V
J 0
(-350 1625);
DISPLAY 0.638298 (-350 1625);
FORCEPROP 1 LAST PACK_TYPE C0805
J 0
(-350 1425);
DISPLAY 0.638298 (-350 1425);
FORCEPROP 1 LAST MATERIAL X6S
J 0
(-350 1525);
DISPLAY 0.638298 (-350 1525);
FORCEPROP 1 LAST $LOCATION C339
J 0
(-350 1725);
DISPLAY 0.638298 (-350 1725);
FORCEPROP 1 LASTPIN (-400 1725) $PN 1
J 0
(-390 1705);
DISPLAY 0.787234 (-390 1705);
FORCEPROP 1 LASTPIN (-400 1525) $PN 2
J 0
(-390 1505);
DISPLAY 0.787234 (-390 1505);
FORCEPROP 2 LAST CDS_LIB pure_quanta
J 0
(-400 1625);
PAINT MONO (-400 1625);
DISPLAY INVISIBLE (-400 1625);
FORCEPROP 1 LAST $LOCATION C339
J 0
(-350 1825);
DISPLAY 1.021277 (-350 1825);
DISPLAY INVISIBLE (-350 1825);
FORCEPROP 2 LAST CDS_LOCATION C339
J 0
(-350 1825);
DISPLAY 1.021277 (-350 1825);
DISPLAY INVISIBLE (-350 1825);
FORCEPROP 2 LAST $SEC 1
J 0
(-350 1825);
DISPLAY 0.680851 (-350 1825);
PAINT MONO (-350 1825);
DISPLAY INVISIBLE (-350 1825);
FORCEPROP 2 LAST CDS_SEC 1
J 0
(-350 1825);
DISPLAY 1.021277 (-350 1825);
DISPLAY INVISIBLE (-350 1825);
FORCEPROP 1 LAST PATH I36
J 0
(-350 1775);
DISPLAY 0.978723 (-350 1775);
PAINT WHITE (-350 1775);
DISPLAY INVISIBLE (-350 1775);
FORCEADD Q_CAP..1
(-4000 2400);
FORCEPROP 1 LAST PART_NUMBER CH647KMEA04
J 0
(-3950 2250);
DISPLAY 0.638298 (-3950 2250);
DISPLAY INVISIBLE (-3950 2250);
FORCEPROP 1 LAST TOLERANCE 20%
J 0
(-3950 2350);
DISPLAY 0.638298 (-3950 2350);
FORCEPROP 1 LAST VOLTAGE 4V
J 0
(-3950 2400);
DISPLAY 0.638298 (-3950 2400);
FORCEPROP 1 LAST PACK_TYPE C0805
J 0
(-3950 2200);
DISPLAY 0.638298 (-3950 2200);
FORCEPROP 1 LAST VALUE 47UF
J 0
(-3950 2450);
DISPLAY 0.638298 (-3950 2450);
FORCEPROP 1 LAST MATERIAL X6S
J 0
(-3950 2300);
DISPLAY 0.638298 (-3950 2300);
FORCEPROP 1 LAST $LOCATION C314
J 0
(-3950 2500);
DISPLAY 0.638298 (-3950 2500);
FORCEPROP 1 LASTPIN (-4000 2500) $PN 1
J 0
(-3990 2480);
DISPLAY 0.787234 (-3990 2480);
FORCEPROP 1 LASTPIN (-4000 2300) $PN 2
J 0
(-3990 2280);
DISPLAY 0.787234 (-3990 2280);
FORCEPROP 2 LAST CDS_LIB pure_quanta
J 0
(-4000 2400);
PAINT MONO (-4000 2400);
DISPLAY INVISIBLE (-4000 2400);
FORCEPROP 1 LAST $LOCATION C314
J 0
(-3950 2600);
DISPLAY 1.021277 (-3950 2600);
DISPLAY INVISIBLE (-3950 2600);
FORCEPROP 2 LAST CDS_LOCATION C314
J 0
(-3950 2600);
DISPLAY 1.021277 (-3950 2600);
DISPLAY INVISIBLE (-3950 2600);
FORCEPROP 2 LAST $SEC 1
J 0
(-3950 2600);
DISPLAY 0.680851 (-3950 2600);
PAINT MONO (-3950 2600);
DISPLAY INVISIBLE (-3950 2600);
FORCEPROP 2 LAST CDS_SEC 1
J 0
(-3950 2600);
DISPLAY 1.021277 (-3950 2600);
DISPLAY INVISIBLE (-3950 2600);
FORCEPROP 1 LAST PATH I37
J 0
(-3950 2550);
DISPLAY 0.978723 (-3950 2550);
PAINT WHITE (-3950 2550);
DISPLAY INVISIBLE (-3950 2550);
FORCEADD Q_CAP..1
(-3550 2400);
FORCEPROP 1 LAST PART_NUMBER CH647KMEA04
J 0
(-3500 2250);
DISPLAY 0.638298 (-3500 2250);
DISPLAY INVISIBLE (-3500 2250);
FORCEPROP 1 LAST TOLERANCE 20%
J 0
(-3500 2350);
DISPLAY 0.638298 (-3500 2350);
FORCEPROP 1 LAST VOLTAGE 4V
J 0
(-3500 2400);
DISPLAY 0.638298 (-3500 2400);
FORCEPROP 1 LAST PACK_TYPE C0805
J 0
(-3500 2200);
DISPLAY 0.638298 (-3500 2200);
FORCEPROP 1 LAST VALUE 47UF
J 0
(-3500 2450);
DISPLAY 0.638298 (-3500 2450);
FORCEPROP 1 LAST MATERIAL X6S
J 0
(-3500 2300);
DISPLAY 0.638298 (-3500 2300);
FORCEPROP 1 LAST $LOCATION C317
J 0
(-3500 2500);
DISPLAY 0.638298 (-3500 2500);
FORCEPROP 1 LASTPIN (-3550 2500) $PN 1
J 0
(-3540 2480);
DISPLAY 0.787234 (-3540 2480);
FORCEPROP 1 LASTPIN (-3550 2300) $PN 2
J 0
(-3540 2280);
DISPLAY 0.787234 (-3540 2280);
FORCEPROP 2 LAST CDS_LIB pure_quanta
J 0
(-3550 2400);
PAINT MONO (-3550 2400);
DISPLAY INVISIBLE (-3550 2400);
FORCEPROP 1 LAST $LOCATION C317
J 0
(-3500 2600);
DISPLAY 1.021277 (-3500 2600);
DISPLAY INVISIBLE (-3500 2600);
FORCEPROP 2 LAST CDS_LOCATION C317
J 0
(-3500 2600);
DISPLAY 1.021277 (-3500 2600);
DISPLAY INVISIBLE (-3500 2600);
FORCEPROP 2 LAST $SEC 1
J 0
(-3500 2600);
DISPLAY 0.680851 (-3500 2600);
PAINT MONO (-3500 2600);
DISPLAY INVISIBLE (-3500 2600);
FORCEPROP 2 LAST CDS_SEC 1
J 0
(-3500 2600);
DISPLAY 1.021277 (-3500 2600);
DISPLAY INVISIBLE (-3500 2600);
FORCEPROP 1 LAST PATH I38
J 0
(-3500 2550);
DISPLAY 0.978723 (-3500 2550);
PAINT WHITE (-3500 2550);
DISPLAY INVISIBLE (-3500 2550);
FORCEADD Q_CAP..1
(-3100 2400);
FORCEPROP 1 LAST PART_NUMBER CH647KMEA04
J 0
(-3050 2250);
DISPLAY 0.638298 (-3050 2250);
DISPLAY INVISIBLE (-3050 2250);
FORCEPROP 1 LAST TOLERANCE 20%
J 0
(-3050 2350);
DISPLAY 0.638298 (-3050 2350);
FORCEPROP 1 LAST VOLTAGE 4V
J 0
(-3050 2400);
DISPLAY 0.638298 (-3050 2400);
FORCEPROP 1 LAST PACK_TYPE C0805
J 0
(-3050 2200);
DISPLAY 0.638298 (-3050 2200);
FORCEPROP 1 LAST VALUE 47UF
J 0
(-3050 2450);
DISPLAY 0.638298 (-3050 2450);
FORCEPROP 1 LAST MATERIAL X6S
J 0
(-3050 2300);
DISPLAY 0.638298 (-3050 2300);
FORCEPROP 1 LAST $LOCATION C320
J 0
(-3050 2500);
DISPLAY 0.638298 (-3050 2500);
FORCEPROP 1 LASTPIN (-3100 2500) $PN 1
J 0
(-3090 2480);
DISPLAY 0.787234 (-3090 2480);
FORCEPROP 1 LASTPIN (-3100 2300) $PN 2
J 0
(-3090 2280);
DISPLAY 0.787234 (-3090 2280);
FORCEPROP 2 LAST CDS_LIB pure_quanta
J 0
(-3100 2400);
PAINT MONO (-3100 2400);
DISPLAY INVISIBLE (-3100 2400);
FORCEPROP 1 LAST $LOCATION C320
J 0
(-3050 2600);
DISPLAY 1.021277 (-3050 2600);
DISPLAY INVISIBLE (-3050 2600);
FORCEPROP 2 LAST CDS_LOCATION C320
J 0
(-3050 2600);
DISPLAY 1.021277 (-3050 2600);
DISPLAY INVISIBLE (-3050 2600);
FORCEPROP 2 LAST $SEC 1
J 0
(-3050 2600);
DISPLAY 0.680851 (-3050 2600);
PAINT MONO (-3050 2600);
DISPLAY INVISIBLE (-3050 2600);
FORCEPROP 2 LAST CDS_SEC 1
J 0
(-3050 2600);
DISPLAY 1.021277 (-3050 2600);
DISPLAY INVISIBLE (-3050 2600);
FORCEPROP 1 LAST PATH I39
J 0
(-3050 2550);
DISPLAY 0.978723 (-3050 2550);
PAINT WHITE (-3050 2550);
DISPLAY INVISIBLE (-3050 2550);
FORCEADD Q_CAP..1
(-3550 -2200);
FORCEPROP 1 LAST PART_NUMBER CH647KMEA04
J 0
(-3500 -2350);
DISPLAY 0.638298 (-3500 -2350);
DISPLAY INVISIBLE (-3500 -2350);
FORCEPROP 1 LAST TOLERANCE 20%
J 0
(-3500 -2250);
DISPLAY 0.638298 (-3500 -2250);
FORCEPROP 1 LAST VOLTAGE 4V
J 0
(-3500 -2200);
DISPLAY 0.638298 (-3500 -2200);
FORCEPROP 1 LAST PACK_TYPE C0805
J 0
(-3500 -2400);
DISPLAY 0.638298 (-3500 -2400);
FORCEPROP 1 LAST VALUE 47UF
J 0
(-3500 -2150);
DISPLAY 0.638298 (-3500 -2150);
FORCEPROP 1 LAST MATERIAL X6S
J 0
(-3500 -2300);
DISPLAY 0.638298 (-3500 -2300);
FORCEPROP 1 LAST $LOCATION C457
J 0
(-3500 -2100);
DISPLAY 0.978723 (-3500 -2100);
FORCEPROP 1 LASTPIN (-3550 -2100) $PN 1
J 0
(-3540 -2120);
DISPLAY 0.787234 (-3540 -2120);
FORCEPROP 1 LASTPIN (-3550 -2300) $PN 2
J 0
(-3540 -2320);
DISPLAY 0.787234 (-3540 -2320);
FORCEPROP 2 LAST CDS_LIB pure_quanta
J 0
(-3550 -2200);
PAINT MONO (-3550 -2200);
DISPLAY INVISIBLE (-3550 -2200);
FORCEPROP 2 LAST CDS_LOCATION C457
J 0
(-3500 -2000);
DISPLAY 1.021277 (-3500 -2000);
DISPLAY INVISIBLE (-3500 -2000);
FORCEPROP 2 LAST $SEC 1
J 0
(-3500 -2000);
DISPLAY 0.680851 (-3500 -2000);
PAINT MONO (-3500 -2000);
DISPLAY INVISIBLE (-3500 -2000);
FORCEPROP 2 LAST CDS_SEC 1
J 0
(-3500 -2000);
DISPLAY 1.021277 (-3500 -2000);
DISPLAY INVISIBLE (-3500 -2000);
FORCEPROP 1 LAST PATH I4
J 0
(-3500 -2050);
DISPLAY 0.978723 (-3500 -2050);
PAINT WHITE (-3500 -2050);
DISPLAY INVISIBLE (-3500 -2050);
FORCEADD Q_CAP..1
(-2650 2400);
FORCEPROP 1 LAST PART_NUMBER CH647KMEA04
J 0
(-2600 2250);
DISPLAY 0.638298 (-2600 2250);
DISPLAY INVISIBLE (-2600 2250);
FORCEPROP 1 LAST TOLERANCE 20%
J 0
(-2600 2350);
DISPLAY 0.638298 (-2600 2350);
FORCEPROP 1 LAST VOLTAGE 4V
J 0
(-2600 2400);
DISPLAY 0.638298 (-2600 2400);
FORCEPROP 1 LAST PACK_TYPE C0805
J 0
(-2600 2200);
DISPLAY 0.638298 (-2600 2200);
FORCEPROP 1 LAST VALUE 47UF
J 0
(-2600 2450);
DISPLAY 0.638298 (-2600 2450);
FORCEPROP 1 LAST MATERIAL X6S
J 0
(-2600 2300);
DISPLAY 0.638298 (-2600 2300);
FORCEPROP 1 LAST $LOCATION C323
J 0
(-2600 2500);
DISPLAY 0.638298 (-2600 2500);
FORCEPROP 1 LASTPIN (-2650 2500) $PN 1
J 0
(-2640 2480);
DISPLAY 0.787234 (-2640 2480);
FORCEPROP 1 LASTPIN (-2650 2300) $PN 2
J 0
(-2640 2280);
DISPLAY 0.787234 (-2640 2280);
FORCEPROP 2 LAST CDS_LIB pure_quanta
J 0
(-2650 2400);
PAINT MONO (-2650 2400);
DISPLAY INVISIBLE (-2650 2400);
FORCEPROP 1 LAST $LOCATION C323
J 0
(-2600 2600);
DISPLAY 1.021277 (-2600 2600);
DISPLAY INVISIBLE (-2600 2600);
FORCEPROP 2 LAST CDS_LOCATION C323
J 0
(-2600 2600);
DISPLAY 1.021277 (-2600 2600);
DISPLAY INVISIBLE (-2600 2600);
FORCEPROP 2 LAST $SEC 1
J 0
(-2600 2600);
DISPLAY 0.680851 (-2600 2600);
PAINT MONO (-2600 2600);
DISPLAY INVISIBLE (-2600 2600);
FORCEPROP 2 LAST CDS_SEC 1
J 0
(-2600 2600);
DISPLAY 1.021277 (-2600 2600);
DISPLAY INVISIBLE (-2600 2600);
FORCEPROP 1 LAST PATH I40
J 0
(-2600 2550);
DISPLAY 0.978723 (-2600 2550);
PAINT WHITE (-2600 2550);
DISPLAY INVISIBLE (-2600 2550);
FORCEADD Q_CAP..1
(-2200 2400);
FORCEPROP 1 LAST PART_NUMBER CH647KMEA04
J 0
(-2150 2250);
DISPLAY 0.638298 (-2150 2250);
DISPLAY INVISIBLE (-2150 2250);
FORCEPROP 1 LAST TOLERANCE 20%
J 0
(-2150 2350);
DISPLAY 0.638298 (-2150 2350);
FORCEPROP 1 LAST VOLTAGE 4V
J 0
(-2150 2400);
DISPLAY 0.638298 (-2150 2400);
FORCEPROP 1 LAST PACK_TYPE C0805
J 0
(-2150 2200);
DISPLAY 0.638298 (-2150 2200);
FORCEPROP 1 LAST VALUE 47UF
J 0
(-2150 2450);
DISPLAY 0.638298 (-2150 2450);
FORCEPROP 1 LAST MATERIAL X6S
J 0
(-2150 2300);
DISPLAY 0.638298 (-2150 2300);
FORCEPROP 1 LAST $LOCATION C326
J 0
(-2150 2500);
DISPLAY 0.638298 (-2150 2500);
FORCEPROP 1 LASTPIN (-2200 2500) $PN 1
J 0
(-2190 2480);
DISPLAY 0.787234 (-2190 2480);
FORCEPROP 1 LASTPIN (-2200 2300) $PN 2
J 0
(-2190 2280);
DISPLAY 0.787234 (-2190 2280);
FORCEPROP 2 LAST CDS_LIB pure_quanta
J 0
(-2200 2400);
PAINT MONO (-2200 2400);
DISPLAY INVISIBLE (-2200 2400);
FORCEPROP 1 LAST $LOCATION C326
J 0
(-2150 2600);
DISPLAY 1.021277 (-2150 2600);
DISPLAY INVISIBLE (-2150 2600);
FORCEPROP 2 LAST CDS_LOCATION C326
J 0
(-2150 2600);
DISPLAY 1.021277 (-2150 2600);
DISPLAY INVISIBLE (-2150 2600);
FORCEPROP 2 LAST $SEC 1
J 0
(-2150 2600);
DISPLAY 0.680851 (-2150 2600);
PAINT MONO (-2150 2600);
DISPLAY INVISIBLE (-2150 2600);
FORCEPROP 2 LAST CDS_SEC 1
J 0
(-2150 2600);
DISPLAY 1.021277 (-2150 2600);
DISPLAY INVISIBLE (-2150 2600);
FORCEPROP 1 LAST PATH I41
J 0
(-2150 2550);
DISPLAY 0.978723 (-2150 2550);
PAINT WHITE (-2150 2550);
DISPLAY INVISIBLE (-2150 2550);
FORCEADD Q_CAP..1
(-1750 2400);
FORCEPROP 1 LAST PART_NUMBER CH647KMEA04
J 0
(-1700 2250);
DISPLAY 0.638298 (-1700 2250);
DISPLAY INVISIBLE (-1700 2250);
FORCEPROP 1 LAST TOLERANCE 20%
J 0
(-1700 2350);
DISPLAY 0.638298 (-1700 2350);
FORCEPROP 1 LAST VOLTAGE 4V
J 0
(-1700 2400);
DISPLAY 0.638298 (-1700 2400);
FORCEPROP 1 LAST PACK_TYPE C0805
J 0
(-1700 2200);
DISPLAY 0.638298 (-1700 2200);
FORCEPROP 1 LAST VALUE 47UF
J 0
(-1700 2450);
DISPLAY 0.638298 (-1700 2450);
FORCEPROP 1 LAST MATERIAL X6S
J 0
(-1700 2300);
DISPLAY 0.638298 (-1700 2300);
FORCEPROP 1 LAST $LOCATION C329
J 0
(-1700 2500);
DISPLAY 0.638298 (-1700 2500);
FORCEPROP 1 LASTPIN (-1750 2500) $PN 1
J 0
(-1740 2480);
DISPLAY 0.787234 (-1740 2480);
FORCEPROP 1 LASTPIN (-1750 2300) $PN 2
J 0
(-1740 2280);
DISPLAY 0.787234 (-1740 2280);
FORCEPROP 2 LAST CDS_LIB pure_quanta
J 0
(-1750 2400);
PAINT MONO (-1750 2400);
DISPLAY INVISIBLE (-1750 2400);
FORCEPROP 1 LAST $LOCATION C329
J 0
(-1700 2600);
DISPLAY 1.021277 (-1700 2600);
DISPLAY INVISIBLE (-1700 2600);
FORCEPROP 2 LAST CDS_LOCATION C329
J 0
(-1700 2600);
DISPLAY 1.021277 (-1700 2600);
DISPLAY INVISIBLE (-1700 2600);
FORCEPROP 2 LAST $SEC 1
J 0
(-1700 2600);
DISPLAY 0.680851 (-1700 2600);
PAINT MONO (-1700 2600);
DISPLAY INVISIBLE (-1700 2600);
FORCEPROP 2 LAST CDS_SEC 1
J 0
(-1700 2600);
DISPLAY 1.021277 (-1700 2600);
DISPLAY INVISIBLE (-1700 2600);
FORCEPROP 1 LAST PATH I42
J 0
(-1700 2550);
DISPLAY 0.978723 (-1700 2550);
PAINT WHITE (-1700 2550);
DISPLAY INVISIBLE (-1700 2550);
FORCEADD Q_CAP..1
(-1300 2400);
FORCEPROP 1 LAST PART_NUMBER CH647KMEA04
J 0
(-1250 2250);
DISPLAY 0.638298 (-1250 2250);
DISPLAY INVISIBLE (-1250 2250);
FORCEPROP 1 LAST TOLERANCE 20%
J 0
(-1250 2350);
DISPLAY 0.638298 (-1250 2350);
FORCEPROP 1 LAST VOLTAGE 4V
J 0
(-1250 2400);
DISPLAY 0.638298 (-1250 2400);
FORCEPROP 1 LAST PACK_TYPE C0805
J 0
(-1250 2200);
DISPLAY 0.638298 (-1250 2200);
FORCEPROP 1 LAST VALUE 47UF
J 0
(-1250 2450);
DISPLAY 0.638298 (-1250 2450);
FORCEPROP 1 LAST MATERIAL X6S
J 0
(-1250 2300);
DISPLAY 0.638298 (-1250 2300);
FORCEPROP 1 LAST $LOCATION C332
J 0
(-1250 2500);
DISPLAY 0.638298 (-1250 2500);
FORCEPROP 1 LASTPIN (-1300 2500) $PN 1
J 0
(-1290 2480);
DISPLAY 0.787234 (-1290 2480);
FORCEPROP 1 LASTPIN (-1300 2300) $PN 2
J 0
(-1290 2280);
DISPLAY 0.787234 (-1290 2280);
FORCEPROP 2 LAST CDS_LIB pure_quanta
J 0
(-1300 2400);
PAINT MONO (-1300 2400);
DISPLAY INVISIBLE (-1300 2400);
FORCEPROP 1 LAST $LOCATION C332
J 0
(-1250 2600);
DISPLAY 1.021277 (-1250 2600);
DISPLAY INVISIBLE (-1250 2600);
FORCEPROP 2 LAST CDS_LOCATION C332
J 0
(-1250 2600);
DISPLAY 1.021277 (-1250 2600);
DISPLAY INVISIBLE (-1250 2600);
FORCEPROP 2 LAST $SEC 1
J 0
(-1250 2600);
DISPLAY 0.680851 (-1250 2600);
PAINT MONO (-1250 2600);
DISPLAY INVISIBLE (-1250 2600);
FORCEPROP 2 LAST CDS_SEC 1
J 0
(-1250 2600);
DISPLAY 1.021277 (-1250 2600);
DISPLAY INVISIBLE (-1250 2600);
FORCEPROP 1 LAST PATH I43
J 0
(-1250 2550);
DISPLAY 0.978723 (-1250 2550);
PAINT WHITE (-1250 2550);
DISPLAY INVISIBLE (-1250 2550);
FORCEADD Q_CAP..1
(-850 2400);
FORCEPROP 1 LAST PART_NUMBER CH647KMEA04
J 0
(-800 2250);
DISPLAY 0.638298 (-800 2250);
DISPLAY INVISIBLE (-800 2250);
FORCEPROP 1 LAST TOLERANCE 20%
J 0
(-800 2350);
DISPLAY 0.638298 (-800 2350);
FORCEPROP 1 LAST VOLTAGE 4V
J 0
(-800 2400);
DISPLAY 0.638298 (-800 2400);
FORCEPROP 1 LAST PACK_TYPE C0805
J 0
(-800 2200);
DISPLAY 0.638298 (-800 2200);
FORCEPROP 1 LAST VALUE 47UF
J 0
(-800 2450);
DISPLAY 0.638298 (-800 2450);
FORCEPROP 1 LAST MATERIAL X6S
J 0
(-800 2300);
DISPLAY 0.638298 (-800 2300);
FORCEPROP 1 LAST $LOCATION C335
J 0
(-800 2500);
DISPLAY 0.638298 (-800 2500);
FORCEPROP 1 LASTPIN (-850 2500) $PN 1
J 0
(-840 2480);
DISPLAY 0.787234 (-840 2480);
FORCEPROP 1 LASTPIN (-850 2300) $PN 2
J 0
(-840 2280);
DISPLAY 0.787234 (-840 2280);
FORCEPROP 2 LAST CDS_LIB pure_quanta
J 0
(-850 2400);
PAINT MONO (-850 2400);
DISPLAY INVISIBLE (-850 2400);
FORCEPROP 1 LAST $LOCATION C335
J 0
(-800 2600);
DISPLAY 1.021277 (-800 2600);
DISPLAY INVISIBLE (-800 2600);
FORCEPROP 2 LAST CDS_LOCATION C335
J 0
(-800 2600);
DISPLAY 1.021277 (-800 2600);
DISPLAY INVISIBLE (-800 2600);
FORCEPROP 2 LAST $SEC 1
J 0
(-800 2600);
DISPLAY 0.680851 (-800 2600);
PAINT MONO (-800 2600);
DISPLAY INVISIBLE (-800 2600);
FORCEPROP 2 LAST CDS_SEC 1
J 0
(-800 2600);
DISPLAY 1.021277 (-800 2600);
DISPLAY INVISIBLE (-800 2600);
FORCEPROP 1 LAST PATH I44
J 0
(-800 2550);
DISPLAY 0.978723 (-800 2550);
PAINT WHITE (-800 2550);
DISPLAY INVISIBLE (-800 2550);
FORCEADD Q_CAP..1
(-400 2400);
FORCEPROP 1 LAST PART_NUMBER CH647KMEA04
J 0
(-350 2250);
DISPLAY 0.638298 (-350 2250);
DISPLAY INVISIBLE (-350 2250);
FORCEPROP 1 LAST TOLERANCE 20%
J 0
(-350 2350);
DISPLAY 0.638298 (-350 2350);
FORCEPROP 1 LAST VOLTAGE 4V
J 0
(-350 2400);
DISPLAY 0.638298 (-350 2400);
FORCEPROP 1 LAST PACK_TYPE C0805
J 0
(-350 2200);
DISPLAY 0.638298 (-350 2200);
FORCEPROP 1 LAST VALUE 47UF
J 0
(-350 2450);
DISPLAY 0.638298 (-350 2450);
FORCEPROP 1 LAST MATERIAL X6S
J 0
(-350 2300);
DISPLAY 0.638298 (-350 2300);
FORCEPROP 1 LAST $LOCATION C338
J 0
(-350 2500);
DISPLAY 0.638298 (-350 2500);
FORCEPROP 1 LASTPIN (-400 2500) $PN 1
J 0
(-390 2480);
DISPLAY 0.787234 (-390 2480);
FORCEPROP 1 LASTPIN (-400 2300) $PN 2
J 0
(-390 2280);
DISPLAY 0.787234 (-390 2280);
FORCEPROP 2 LAST CDS_LIB pure_quanta
J 0
(-400 2400);
PAINT MONO (-400 2400);
DISPLAY INVISIBLE (-400 2400);
FORCEPROP 1 LAST $LOCATION C338
J 0
(-350 2600);
DISPLAY 1.021277 (-350 2600);
DISPLAY INVISIBLE (-350 2600);
FORCEPROP 2 LAST CDS_LOCATION C338
J 0
(-350 2600);
DISPLAY 1.021277 (-350 2600);
DISPLAY INVISIBLE (-350 2600);
FORCEPROP 2 LAST $SEC 1
J 0
(-350 2600);
DISPLAY 0.680851 (-350 2600);
PAINT MONO (-350 2600);
DISPLAY INVISIBLE (-350 2600);
FORCEPROP 2 LAST CDS_SEC 1
J 0
(-350 2600);
DISPLAY 1.021277 (-350 2600);
DISPLAY INVISIBLE (-350 2600);
FORCEPROP 1 LAST PATH I45
J 0
(-350 2550);
DISPLAY 0.978723 (-350 2550);
PAINT WHITE (-350 2550);
DISPLAY INVISIBLE (-350 2550);
FORCEADD Q_CAP..1
(-100 -1250);
FORCEPROP 1 LAST PART_NUMBER CH647KMEA04
J 0
(-50 -1400);
DISPLAY 0.638298 (-50 -1400);
DISPLAY INVISIBLE (-50 -1400);
FORCEPROP 1 LAST PACK_TYPE C0805
J 0
(-50 -1450);
DISPLAY 0.638298 (-50 -1450);
FORCEPROP 1 LAST VALUE 47UF
J 0
(-50 -1200);
DISPLAY 0.638298 (-50 -1200);
FORCEPROP 1 LAST MATERIAL X6S
J 0
(-50 -1350);
DISPLAY 0.638298 (-50 -1350);
FORCEPROP 1 LAST VOLTAGE 4V
J 0
(-50 -1250);
DISPLAY 0.638298 (-50 -1250);
FORCEPROP 1 LAST TOLERANCE 20%
J 0
(-50 -1300);
DISPLAY 0.638298 (-50 -1300);
FORCEPROP 1 LAST $LOCATION C1388
J 0
(-50 -1150);
DISPLAY 0.978723 (-50 -1150);
FORCEPROP 1 LASTPIN (-100 -1150) $PN 1
J 0
(-90 -1170);
DISPLAY 0.787234 (-90 -1170);
FORCEPROP 1 LASTPIN (-100 -1350) $PN 2
J 0
(-90 -1370);
DISPLAY 0.787234 (-90 -1370);
FORCEPROP 2 LAST CDS_LIB pure_quanta
J 0
(-100 -1250);
PAINT MONO (-100 -1250);
DISPLAY INVISIBLE (-100 -1250);
FORCEPROP 2 LAST CDS_LOCATION C1388
J 0
(-50 -1050);
DISPLAY 1.021277 (-50 -1050);
DISPLAY INVISIBLE (-50 -1050);
FORCEPROP 2 LAST $SEC 1
J 0
(-50 -1050);
DISPLAY 0.680851 (-50 -1050);
PAINT MONO (-50 -1050);
DISPLAY INVISIBLE (-50 -1050);
FORCEPROP 2 LAST CDS_SEC 1
J 0
(-50 -1050);
DISPLAY 1.021277 (-50 -1050);
DISPLAY INVISIBLE (-50 -1050);
FORCEPROP 1 LAST PATH I46
J 0
(-50 -1100);
DISPLAY 0.978723 (-50 -1100);
PAINT WHITE (-50 -1100);
DISPLAY INVISIBLE (-50 -1100);
FORCEADD UNIVERSAL_POWER..1
(-100 -975);
FORCEPROP 3 LASTPIN (-100 -1025) SIG_NAME PVPP_HBM_CPU1\g
J 0
(-90 -1015);
DISPLAY 0.659574 (-90 -1015);
PAINT MONO (-90 -1015);
DISPLAY INVISIBLE (-90 -1015);
FORCEPROP 1 LAST HDL_POWER PVPP_HBM_CPU1
J 1
(75 -925);
DISPLAY 0.872340 (75 -925);
PAINT GREEN (75 -925);
FORCEPROP 2 LAST CDS_LIB logical_power
J 0
(-100 -975);
PAINT MONO (-100 -975);
DISPLAY INVISIBLE (-100 -975);
FORCEPROP 1 LAST PATH I47
J 0
(-50 -950);
DISPLAY 0.872340 (-50 -950);
PAINT AQUA (-50 -950);
DISPLAY INVISIBLE (-50 -950);
FORCEADD Q_CAP..1
(350 -1250);
FORCEPROP 1 LAST PART_NUMBER CH647KMEA04
J 0
(400 -1400);
DISPLAY 0.638298 (400 -1400);
DISPLAY INVISIBLE (400 -1400);
FORCEPROP 1 LAST VALUE 47UF
J 0
(400 -1200);
DISPLAY 0.638298 (400 -1200);
FORCEPROP 1 LAST TOLERANCE 20%
J 0
(400 -1300);
DISPLAY 0.638298 (400 -1300);
FORCEPROP 1 LAST MATERIAL X6S
J 0
(400 -1350);
DISPLAY 0.638298 (400 -1350);
FORCEPROP 1 LAST VOLTAGE 4V
J 0
(400 -1250);
DISPLAY 0.638298 (400 -1250);
FORCEPROP 1 LAST PACK_TYPE C0805
J 0
(400 -1450);
DISPLAY 0.638298 (400 -1450);
FORCEPROP 1 LAST $LOCATION C1390
J 0
(400 -1150);
DISPLAY 0.978723 (400 -1150);
FORCEPROP 1 LASTPIN (350 -1150) $PN 1
J 0
(360 -1170);
DISPLAY 0.787234 (360 -1170);
FORCEPROP 1 LASTPIN (350 -1350) $PN 2
J 0
(360 -1370);
DISPLAY 0.787234 (360 -1370);
FORCEPROP 2 LAST CDS_LIB pure_quanta
J 0
(350 -1250);
PAINT MONO (350 -1250);
DISPLAY INVISIBLE (350 -1250);
FORCEPROP 2 LAST CDS_LOCATION C1390
J 0
(400 -1050);
DISPLAY 1.021277 (400 -1050);
DISPLAY INVISIBLE (400 -1050);
FORCEPROP 2 LAST $SEC 1
J 0
(400 -1050);
DISPLAY 0.680851 (400 -1050);
PAINT MONO (400 -1050);
DISPLAY INVISIBLE (400 -1050);
FORCEPROP 2 LAST CDS_SEC 1
J 0
(400 -1050);
DISPLAY 1.021277 (400 -1050);
DISPLAY INVISIBLE (400 -1050);
FORCEPROP 1 LAST PATH I48
J 0
(400 -1100);
DISPLAY 0.978723 (400 -1100);
PAINT WHITE (400 -1100);
DISPLAY INVISIBLE (400 -1100);
FORCEADD Q_CAP..1
(-100 -225);
FORCEPROP 1 LAST PART_NUMBER CH647KMEA04
J 0
(-50 -375);
DISPLAY 0.638298 (-50 -375);
DISPLAY INVISIBLE (-50 -375);
FORCEPROP 1 LAST PACK_TYPE C0805
J 0
(-50 -425);
DISPLAY 0.638298 (-50 -425);
FORCEPROP 1 LAST VALUE 47UF
J 0
(-50 -175);
DISPLAY 0.638298 (-50 -175);
FORCEPROP 1 LAST TOLERANCE 20%
J 0
(-50 -275);
DISPLAY 0.638298 (-50 -275);
FORCEPROP 1 LAST MATERIAL X6S
J 0
(-50 -325);
DISPLAY 0.638298 (-50 -325);
FORCEPROP 1 LAST VOLTAGE 4V
J 0
(-50 -225);
DISPLAY 0.638298 (-50 -225);
FORCEPROP 1 LAST $LOCATION C1387
J 0
(-50 -125);
DISPLAY 0.978723 (-50 -125);
FORCEPROP 1 LASTPIN (-100 -125) $PN 1
J 0
(-90 -145);
DISPLAY 0.787234 (-90 -145);
FORCEPROP 1 LASTPIN (-100 -325) $PN 2
J 0
(-90 -345);
DISPLAY 0.787234 (-90 -345);
FORCEPROP 2 LAST CDS_LIB pure_quanta
J 0
(-100 -225);
PAINT MONO (-100 -225);
DISPLAY INVISIBLE (-100 -225);
FORCEPROP 2 LAST CDS_LOCATION C1387
J 0
(-50 -25);
DISPLAY 1.021277 (-50 -25);
DISPLAY INVISIBLE (-50 -25);
FORCEPROP 2 LAST $SEC 1
J 0
(-50 -25);
DISPLAY 0.680851 (-50 -25);
PAINT MONO (-50 -25);
DISPLAY INVISIBLE (-50 -25);
FORCEPROP 2 LAST CDS_SEC 1
J 0
(-50 -25);
DISPLAY 1.021277 (-50 -25);
DISPLAY INVISIBLE (-50 -25);
FORCEPROP 1 LAST PATH I49
J 0
(-50 -75);
DISPLAY 0.978723 (-50 -75);
PAINT WHITE (-50 -75);
DISPLAY INVISIBLE (-50 -75);
FORCEADD Q_CAP..1
(-3100 -2200);
FORCEPROP 1 LAST PART_NUMBER CH647KMEA04
J 0
(-3050 -2350);
DISPLAY 0.638298 (-3050 -2350);
DISPLAY INVISIBLE (-3050 -2350);
FORCEPROP 1 LAST VALUE 47UF
J 0
(-3050 -2150);
DISPLAY 0.638298 (-3050 -2150);
FORCEPROP 1 LAST MATERIAL X6S
J 0
(-3050 -2300);
DISPLAY 0.638298 (-3050 -2300);
FORCEPROP 1 LAST VOLTAGE 4V
J 0
(-3050 -2200);
DISPLAY 0.638298 (-3050 -2200);
FORCEPROP 1 LAST TOLERANCE 20%
J 0
(-3050 -2250);
DISPLAY 0.638298 (-3050 -2250);
FORCEPROP 1 LAST PACK_TYPE C0805
J 0
(-3050 -2400);
DISPLAY 0.638298 (-3050 -2400);
FORCEPROP 1 LAST $LOCATION C461
J 0
(-3050 -2100);
DISPLAY 0.978723 (-3050 -2100);
FORCEPROP 1 LASTPIN (-3100 -2100) $PN 1
J 0
(-3090 -2120);
DISPLAY 0.787234 (-3090 -2120);
FORCEPROP 1 LASTPIN (-3100 -2300) $PN 2
J 0
(-3090 -2320);
DISPLAY 0.787234 (-3090 -2320);
FORCEPROP 2 LAST CDS_LIB pure_quanta
J 0
(-3100 -2200);
PAINT MONO (-3100 -2200);
DISPLAY INVISIBLE (-3100 -2200);
FORCEPROP 2 LAST CDS_LOCATION C461
J 0
(-3050 -2000);
DISPLAY 1.021277 (-3050 -2000);
DISPLAY INVISIBLE (-3050 -2000);
FORCEPROP 2 LAST $SEC 1
J 0
(-3050 -2000);
DISPLAY 0.680851 (-3050 -2000);
PAINT MONO (-3050 -2000);
DISPLAY INVISIBLE (-3050 -2000);
FORCEPROP 2 LAST CDS_SEC 1
J 0
(-3050 -2000);
DISPLAY 1.021277 (-3050 -2000);
DISPLAY INVISIBLE (-3050 -2000);
FORCEPROP 1 LAST PATH I5
J 0
(-3050 -2050);
DISPLAY 0.978723 (-3050 -2050);
PAINT WHITE (-3050 -2050);
DISPLAY INVISIBLE (-3050 -2050);
FORCEADD UNIVERSAL_POWER..1
(-100 50);
FORCEPROP 3 LASTPIN (-100 0) SIG_NAME PVNN_MAIN_CPU1\g
J 0
(-90 10);
DISPLAY 0.659574 (-90 10);
PAINT MONO (-90 10);
DISPLAY INVISIBLE (-90 10);
FORCEPROP 1 LAST HDL_POWER PVNN_MAIN_CPU1
J 1
(100 100);
DISPLAY 0.872340 (100 100);
PAINT GREEN (100 100);
FORCEPROP 2 LAST CDS_LIB logical_power
J 0
(-100 50);
PAINT MONO (-100 50);
DISPLAY INVISIBLE (-100 50);
FORCEPROP 1 LAST PATH I50
J 0
(-50 75);
DISPLAY 0.872340 (-50 75);
PAINT AQUA (-50 75);
DISPLAY INVISIBLE (-50 75);
FORCEADD Q_CAP..1
(350 -225);
FORCEPROP 1 LAST PART_NUMBER CH647LME900
J 0
(400 -375);
DISPLAY 0.638298 (400 -375);
DISPLAY INVISIBLE (400 -375);
FORCEPROP 1 LAST TOLERANCE 20%
J 0
(400 -275);
DISPLAY 0.638298 (400 -275);
FORCEPROP 1 LAST MATERIAL X6S
J 0
(400 -325);
DISPLAY 0.638298 (400 -325);
FORCEPROP 1 LAST PACK_TYPE C0603
J 0
(400 -425);
DISPLAY 0.638298 (400 -425);
FORCEPROP 1 LAST VOLTAGE 2.5V
J 0
(400 -225);
DISPLAY 0.638298 (400 -225);
FORCEPROP 1 LAST VALUE 47UF
J 0
(400 -175);
DISPLAY 0.638298 (400 -175);
FORCEPROP 1 LAST $LOCATION C1389
J 0
(400 -125);
DISPLAY 0.978723 (400 -125);
FORCEPROP 1 LASTPIN (350 -125) $PN 1
J 0
(360 -145);
DISPLAY 0.787234 (360 -145);
FORCEPROP 1 LASTPIN (350 -325) $PN 2
J 0
(360 -345);
DISPLAY 0.787234 (360 -345);
FORCEPROP 2 LAST CDS_LIB pure_quanta
J 0
(350 -225);
PAINT MONO (350 -225);
DISPLAY INVISIBLE (350 -225);
FORCEPROP 2 LAST CDS_LOCATION C1389
J 0
(400 -25);
DISPLAY 1.021277 (400 -25);
DISPLAY INVISIBLE (400 -25);
FORCEPROP 2 LAST $SEC 1
J 0
(400 -25);
DISPLAY 0.680851 (400 -25);
PAINT MONO (400 -25);
DISPLAY INVISIBLE (400 -25);
FORCEPROP 2 LAST CDS_SEC 1
J 0
(400 -25);
DISPLAY 1.021277 (400 -25);
DISPLAY INVISIBLE (400 -25);
FORCEPROP 1 LAST PATH I51
J 0
(400 -75);
DISPLAY 0.978723 (400 -75);
PAINT WHITE (400 -75);
DISPLAY INVISIBLE (400 -75);
FORCEADD Q_CAP..1
(800 -225);
FORCEPROP 1 LAST PART_NUMBER CH647LME900
J 0
(850 -375);
DISPLAY 0.638298 (850 -375);
DISPLAY INVISIBLE (850 -375);
FORCEPROP 1 LAST TOLERANCE 20%
J 0
(850 -275);
DISPLAY 0.638298 (850 -275);
FORCEPROP 1 LAST MATERIAL X6S
J 0
(850 -325);
DISPLAY 0.638298 (850 -325);
FORCEPROP 1 LAST VALUE 47UF
J 0
(850 -175);
DISPLAY 0.638298 (850 -175);
FORCEPROP 1 LAST VOLTAGE 2.5V
J 0
(850 -225);
DISPLAY 0.638298 (850 -225);
FORCEPROP 1 LAST PACK_TYPE C0603
J 0
(850 -425);
DISPLAY 0.638298 (850 -425);
FORCEPROP 1 LAST $LOCATION C1391
J 0
(850 -125);
DISPLAY 0.978723 (850 -125);
FORCEPROP 1 LASTPIN (800 -125) $PN 1
J 0
(810 -145);
DISPLAY 0.787234 (810 -145);
FORCEPROP 1 LASTPIN (800 -325) $PN 2
J 0
(810 -345);
DISPLAY 0.787234 (810 -345);
FORCEPROP 2 LAST CDS_LIB pure_quanta
J 0
(800 -225);
PAINT MONO (800 -225);
DISPLAY INVISIBLE (800 -225);
FORCEPROP 2 LAST CDS_LOCATION C1391
J 0
(850 -25);
DISPLAY 1.021277 (850 -25);
DISPLAY INVISIBLE (850 -25);
FORCEPROP 2 LAST $SEC 1
J 0
(850 -25);
DISPLAY 0.680851 (850 -25);
PAINT MONO (850 -25);
DISPLAY INVISIBLE (850 -25);
FORCEPROP 2 LAST CDS_SEC 1
J 0
(850 -25);
DISPLAY 1.021277 (850 -25);
DISPLAY INVISIBLE (850 -25);
FORCEPROP 1 LAST PATH I52
J 0
(850 -75);
DISPLAY 0.978723 (850 -75);
PAINT WHITE (850 -75);
DISPLAY INVISIBLE (850 -75);
FORCEADD Q_CAP..1
(800 -1250);
FORCEPROP 1 LAST PART_NUMBER CH647KMEA04
J 0
(850 -1400);
DISPLAY 0.638298 (850 -1400);
DISPLAY INVISIBLE (850 -1400);
FORCEPROP 1 LAST PACK_TYPE C0805
J 0
(850 -1450);
DISPLAY 0.638298 (850 -1450);
FORCEPROP 1 LAST VALUE 47UF
J 0
(850 -1200);
DISPLAY 0.638298 (850 -1200);
FORCEPROP 1 LAST TOLERANCE 20%
J 0
(850 -1300);
DISPLAY 0.638298 (850 -1300);
FORCEPROP 1 LAST MATERIAL X6S
J 0
(850 -1350);
DISPLAY 0.638298 (850 -1350);
FORCEPROP 1 LAST VOLTAGE 4V
J 0
(850 -1250);
DISPLAY 0.638298 (850 -1250);
FORCEPROP 1 LAST $LOCATION C1392
J 0
(850 -1150);
DISPLAY 0.978723 (850 -1150);
FORCEPROP 1 LASTPIN (800 -1150) $PN 1
J 0
(810 -1170);
DISPLAY 0.787234 (810 -1170);
FORCEPROP 1 LASTPIN (800 -1350) $PN 2
J 0
(810 -1370);
DISPLAY 0.787234 (810 -1370);
FORCEPROP 2 LAST CDS_LIB pure_quanta
J 0
(800 -1250);
PAINT MONO (800 -1250);
DISPLAY INVISIBLE (800 -1250);
FORCEPROP 2 LAST CDS_LOCATION C1392
J 0
(850 -1050);
DISPLAY 1.021277 (850 -1050);
DISPLAY INVISIBLE (850 -1050);
FORCEPROP 2 LAST $SEC 1
J 0
(850 -1050);
DISPLAY 0.680851 (850 -1050);
PAINT MONO (850 -1050);
DISPLAY INVISIBLE (850 -1050);
FORCEPROP 2 LAST CDS_SEC 1
J 0
(850 -1050);
DISPLAY 1.021277 (850 -1050);
DISPLAY INVISIBLE (850 -1050);
FORCEPROP 1 LAST PATH I53
J 0
(850 -1100);
DISPLAY 0.978723 (850 -1100);
PAINT WHITE (850 -1100);
DISPLAY INVISIBLE (850 -1100);
FORCEADD UNIVERSAL_GND..1
(1250 -1600);
FORCEPROP 3 LASTPIN (1250 -1550) SIG_NAME GND\g
J 0
(1260 -1540);
DISPLAY 0.659574 (1260 -1540);
PAINT MONO (1260 -1540);
DISPLAY INVISIBLE (1260 -1540);
FORCEPROP 2 LAST CDS_LIB logical_power
J 0
(1250 -1600);
DISPLAY INVISIBLE (1250 -1600);
FORCEPROP 1 LAST HDL_POWER GND
J 1
(1275 -1675);
DISPLAY 0.872340 (1275 -1675);
PAINT GREEN (1275 -1675);
DISPLAY INVISIBLE (1275 -1675);
FORCEPROP 1 LAST PATH I54
J 0
(1325 -1600);
DISPLAY 0.872340 (1325 -1600);
PAINT AQUA (1325 -1600);
DISPLAY INVISIBLE (1325 -1600);
FORCEADD Q_CAP..1
(1250 -1250);
FORCEPROP 1 LAST PART_NUMBER CH4221KEE00
J 0
(1300 -1400);
DISPLAY 0.638298 (1300 -1400);
DISPLAY INVISIBLE (1300 -1400);
FORCEPROP 1 LAST MATERIAL X6S
J 0
(1300 -1350);
DISPLAY 0.638298 (1300 -1350);
FORCEPROP 1 LAST VALUE 0.22UF
J 0
(1300 -1200);
DISPLAY 0.638298 (1300 -1200);
FORCEPROP 1 LAST PACK_TYPE C0201
J 0
(1300 -1450);
DISPLAY 0.638298 (1300 -1450);
FORCEPROP 1 LAST TOLERANCE 10%
J 0
(1300 -1300);
DISPLAY 0.638298 (1300 -1300);
FORCEPROP 1 LAST VOLTAGE 6.3V
J 0
(1300 -1250);
DISPLAY 0.638298 (1300 -1250);
FORCEPROP 1 LAST $LOCATION C1437
J 0
(1300 -1150);
DISPLAY 0.978723 (1300 -1150);
FORCEPROP 1 LASTPIN (1250 -1150) $PN 1
J 0
(1260 -1170);
DISPLAY 0.787234 (1260 -1170);
PAINT MONO (1260 -1170);
FORCEPROP 1 LASTPIN (1250 -1350) $PN 2
J 0
(1260 -1370);
DISPLAY 0.787234 (1260 -1370);
PAINT MONO (1260 -1370);
FORCEPROP 2 LAST CDS_LIB pure_quanta
J 0
(1250 -1250);
DISPLAY INVISIBLE (1250 -1250);
FORCEPROP 0 LAST CDS_LOCATION C1437
J 0
(1300 -1100);
DISPLAY 1.021277 (1300 -1100);
DISPLAY INVISIBLE (1300 -1100);
FORCEPROP 0 LAST $SEC 1
J 0
(1300 -1100);
DISPLAY 0.680851 (1300 -1100);
PAINT MONO (1300 -1100);
DISPLAY INVISIBLE (1300 -1100);
FORCEPROP 0 LAST CDS_SEC 1
J 0
(1300 -1100);
DISPLAY 1.021277 (1300 -1100);
DISPLAY INVISIBLE (1300 -1100);
FORCEPROP 1 LAST PATH I55
J 0
(1300 -1100);
DISPLAY 0.978723 (1300 -1100);
PAINT WHITE (1300 -1100);
DISPLAY INVISIBLE (1300 -1100);
FORCEADD UNIVERSAL_GND..1
(1250 -575);
FORCEPROP 3 LASTPIN (1250 -525) SIG_NAME GND\g
J 0
(1260 -515);
DISPLAY 0.659574 (1260 -515);
PAINT MONO (1260 -515);
DISPLAY INVISIBLE (1260 -515);
FORCEPROP 2 LAST CDS_LIB logical_power
J 0
(1250 -575);
PAINT MONO (1250 -575);
DISPLAY INVISIBLE (1250 -575);
FORCEPROP 1 LAST HDL_POWER GND
J 1
(1275 -650);
DISPLAY 0.872340 (1275 -650);
PAINT GREEN (1275 -650);
DISPLAY INVISIBLE (1275 -650);
FORCEPROP 1 LAST PATH I56
J 0
(1325 -575);
DISPLAY 0.872340 (1325 -575);
PAINT AQUA (1325 -575);
DISPLAY INVISIBLE (1325 -575);
FORCEADD Q_CAP..1
(1250 -225);
FORCEPROP 1 LAST PART_NUMBER CH647LME900
J 0
(1300 -375);
DISPLAY 0.638298 (1300 -375);
DISPLAY INVISIBLE (1300 -375);
FORCEPROP 1 LAST TOLERANCE 20%
J 0
(1300 -275);
DISPLAY 0.638298 (1300 -275);
FORCEPROP 1 LAST MATERIAL X6S
J 0
(1300 -325);
DISPLAY 0.638298 (1300 -325);
FORCEPROP 1 LAST VALUE 47UF
J 0
(1300 -175);
DISPLAY 0.638298 (1300 -175);
FORCEPROP 1 LAST VOLTAGE 2.5V
J 0
(1300 -225);
DISPLAY 0.638298 (1300 -225);
FORCEPROP 1 LAST PACK_TYPE C0603
J 0
(1300 -425);
DISPLAY 0.638298 (1300 -425);
FORCEPROP 1 LAST $LOCATION C1393
J 0
(1300 -125);
DISPLAY 0.978723 (1300 -125);
FORCEPROP 1 LASTPIN (1250 -125) $PN 1
J 0
(1260 -145);
DISPLAY 0.787234 (1260 -145);
FORCEPROP 1 LASTPIN (1250 -325) $PN 2
J 0
(1260 -345);
DISPLAY 0.787234 (1260 -345);
FORCEPROP 2 LAST CDS_LIB pure_quanta
J 0
(1250 -225);
PAINT MONO (1250 -225);
DISPLAY INVISIBLE (1250 -225);
FORCEPROP 2 LAST CDS_LOCATION C1393
J 0
(1300 -25);
DISPLAY 1.021277 (1300 -25);
DISPLAY INVISIBLE (1300 -25);
FORCEPROP 2 LAST $SEC 1
J 0
(1300 -25);
DISPLAY 0.680851 (1300 -25);
PAINT MONO (1300 -25);
DISPLAY INVISIBLE (1300 -25);
FORCEPROP 2 LAST CDS_SEC 1
J 0
(1300 -25);
DISPLAY 1.021277 (1300 -25);
DISPLAY INVISIBLE (1300 -25);
FORCEPROP 1 LAST PATH I57
J 0
(1300 -75);
DISPLAY 0.978723 (1300 -75);
PAINT WHITE (1300 -75);
DISPLAY INVISIBLE (1300 -75);
FORCEADD Q_CAP..1
(50 1625);
FORCEPROP 1 LAST PART_NUMBER CH647KMEA04
J 0
(100 1475);
DISPLAY 0.638298 (100 1475);
DISPLAY INVISIBLE (100 1475);
FORCEPROP 1 LAST VOLTAGE 4V
J 0
(100 1625);
DISPLAY 0.638298 (100 1625);
FORCEPROP 1 LAST VALUE 47UF
J 0
(100 1675);
DISPLAY 0.638298 (100 1675);
FORCEPROP 1 LAST TOLERANCE 20%
J 0
(100 1575);
DISPLAY 0.638298 (100 1575);
FORCEPROP 1 LAST PACK_TYPE C0805
J 0
(100 1425);
DISPLAY 0.638298 (100 1425);
FORCEPROP 1 LAST MATERIAL X6S
J 0
(100 1525);
DISPLAY 0.638298 (100 1525);
FORCEPROP 1 LAST $LOCATION C313
J 0
(100 1725);
DISPLAY 0.638298 (100 1725);
FORCEPROP 1 LASTPIN (50 1725) $PN 1
J 0
(60 1705);
DISPLAY 0.787234 (60 1705);
FORCEPROP 1 LASTPIN (50 1525) $PN 2
J 0
(60 1505);
DISPLAY 0.787234 (60 1505);
FORCEPROP 2 LAST CDS_LIB pure_quanta
J 0
(50 1625);
PAINT MONO (50 1625);
DISPLAY INVISIBLE (50 1625);
FORCEPROP 1 LAST $LOCATION C313
J 0
(100 1825);
DISPLAY 1.021277 (100 1825);
DISPLAY INVISIBLE (100 1825);
FORCEPROP 2 LAST CDS_LOCATION C313
J 0
(100 1825);
DISPLAY 1.021277 (100 1825);
DISPLAY INVISIBLE (100 1825);
FORCEPROP 2 LAST $SEC 1
J 0
(100 1825);
DISPLAY 0.680851 (100 1825);
PAINT MONO (100 1825);
DISPLAY INVISIBLE (100 1825);
FORCEPROP 2 LAST CDS_SEC 1
J 0
(100 1825);
DISPLAY 1.021277 (100 1825);
DISPLAY INVISIBLE (100 1825);
FORCEPROP 1 LAST PATH I58
J 0
(100 1775);
DISPLAY 0.978723 (100 1775);
PAINT WHITE (100 1775);
DISPLAY INVISIBLE (100 1775);
FORCEADD UNIVERSAL_GND..1
(500 1275);
FORCEPROP 3 LASTPIN (500 1325) SIG_NAME GND\g
J 0
(510 1335);
DISPLAY 0.659574 (510 1335);
PAINT MONO (510 1335);
DISPLAY INVISIBLE (510 1335);
FORCEPROP 2 LAST CDS_LIB logical_power
J 0
(500 1275);
PAINT MONO (500 1275);
DISPLAY INVISIBLE (500 1275);
FORCEPROP 1 LAST HDL_POWER GND
J 1
(525 1200);
DISPLAY 0.872340 (525 1200);
PAINT GREEN (525 1200);
DISPLAY INVISIBLE (525 1200);
FORCEPROP 1 LAST PATH I59
J 0
(575 1275);
DISPLAY 0.872340 (575 1275);
PAINT AQUA (575 1275);
DISPLAY INVISIBLE (575 1275);
FORCEADD UNIVERSAL_GND..1
(-2650 -2550);
FORCEPROP 3 LASTPIN (-2650 -2500) SIG_NAME GND\g
J 0
(-2640 -2490);
DISPLAY 0.659574 (-2640 -2490);
PAINT MONO (-2640 -2490);
DISPLAY INVISIBLE (-2640 -2490);
FORCEPROP 2 LAST CDS_LIB logical_power
J 0
(-2650 -2550);
PAINT MONO (-2650 -2550);
DISPLAY INVISIBLE (-2650 -2550);
FORCEPROP 1 LAST HDL_POWER GND
J 1
(-2625 -2625);
DISPLAY 0.872340 (-2625 -2625);
PAINT GREEN (-2625 -2625);
DISPLAY INVISIBLE (-2625 -2625);
FORCEPROP 1 LAST PATH I6
J 0
(-2575 -2550);
DISPLAY 0.872340 (-2575 -2550);
PAINT AQUA (-2575 -2550);
DISPLAY INVISIBLE (-2575 -2550);
FORCEADD Q_CAP..1
(500 1625);
FORCEPROP 1 LAST PART_NUMBER CH647KMEA04
J 0
(550 1475);
DISPLAY 0.638298 (550 1475);
DISPLAY INVISIBLE (550 1475);
FORCEPROP 1 LAST TOLERANCE 20%
J 0
(550 1575);
DISPLAY 0.638298 (550 1575);
FORCEPROP 1 LAST VALUE 47UF
J 0
(550 1675);
DISPLAY 0.638298 (550 1675);
FORCEPROP 1 LAST VOLTAGE 4V
J 0
(550 1625);
DISPLAY 0.638298 (550 1625);
FORCEPROP 1 LAST PACK_TYPE C0805
J 0
(550 1425);
DISPLAY 0.638298 (550 1425);
FORCEPROP 1 LAST MATERIAL X6S
J 0
(550 1525);
DISPLAY 0.638298 (550 1525);
FORCEPROP 1 LAST $LOCATION C316
J 0
(550 1725);
DISPLAY 0.638298 (550 1725);
FORCEPROP 1 LASTPIN (500 1725) $PN 1
J 0
(510 1705);
DISPLAY 0.787234 (510 1705);
FORCEPROP 1 LASTPIN (500 1525) $PN 2
J 0
(510 1505);
DISPLAY 0.787234 (510 1505);
FORCEPROP 2 LAST CDS_LIB pure_quanta
J 0
(500 1625);
PAINT MONO (500 1625);
DISPLAY INVISIBLE (500 1625);
FORCEPROP 1 LAST $LOCATION C316
J 0
(550 1825);
DISPLAY 1.021277 (550 1825);
DISPLAY INVISIBLE (550 1825);
FORCEPROP 2 LAST CDS_LOCATION C316
J 0
(550 1825);
DISPLAY 1.021277 (550 1825);
DISPLAY INVISIBLE (550 1825);
FORCEPROP 2 LAST $SEC 1
J 0
(550 1825);
DISPLAY 0.680851 (550 1825);
PAINT MONO (550 1825);
DISPLAY INVISIBLE (550 1825);
FORCEPROP 2 LAST CDS_SEC 1
J 0
(550 1825);
DISPLAY 1.021277 (550 1825);
DISPLAY INVISIBLE (550 1825);
FORCEPROP 1 LAST PATH I60
J 0
(550 1775);
DISPLAY 0.978723 (550 1775);
PAINT WHITE (550 1775);
DISPLAY INVISIBLE (550 1775);
FORCEADD UNIVERSAL_GND..1
(950 2050);
FORCEPROP 3 LASTPIN (950 2100) SIG_NAME GND\g
J 0
(960 2110);
DISPLAY 0.659574 (960 2110);
PAINT MONO (960 2110);
DISPLAY INVISIBLE (960 2110);
FORCEPROP 2 LAST CDS_LIB logical_power
J 0
(950 2050);
PAINT MONO (950 2050);
DISPLAY INVISIBLE (950 2050);
FORCEPROP 1 LAST HDL_POWER GND
J 1
(975 1975);
DISPLAY 0.872340 (975 1975);
PAINT GREEN (975 1975);
DISPLAY INVISIBLE (975 1975);
FORCEPROP 1 LAST PATH I61
J 0
(1025 2050);
DISPLAY 0.872340 (1025 2050);
PAINT AQUA (1025 2050);
DISPLAY INVISIBLE (1025 2050);
FORCEADD UNIVERSAL_GND..1
(2275 2050);
FORCEPROP 3 LASTPIN (2275 2100) SIG_NAME GND\g
J 0
(2285 2110);
DISPLAY 0.659574 (2285 2110);
PAINT MONO (2285 2110);
DISPLAY INVISIBLE (2285 2110);
FORCEPROP 2 LAST CDS_LIB logical_power
J 0
(2275 2050);
PAINT MONO (2275 2050);
DISPLAY INVISIBLE (2275 2050);
FORCEPROP 1 LAST HDL_POWER GND
J 1
(2300 1975);
DISPLAY 0.872340 (2300 1975);
PAINT GREEN (2300 1975);
DISPLAY INVISIBLE (2300 1975);
FORCEPROP 1 LAST PATH I62
J 0
(2350 2050);
DISPLAY 0.872340 (2350 2050);
PAINT AQUA (2350 2050);
DISPLAY INVISIBLE (2350 2050);
FORCEADD Q_CAP..1
(50 2400);
FORCEPROP 1 LAST PART_NUMBER CH647KMEA04
J 0
(100 2250);
DISPLAY 0.638298 (100 2250);
DISPLAY INVISIBLE (100 2250);
FORCEPROP 1 LAST TOLERANCE 20%
J 0
(100 2350);
DISPLAY 0.638298 (100 2350);
FORCEPROP 1 LAST VOLTAGE 4V
J 0
(100 2400);
DISPLAY 0.638298 (100 2400);
FORCEPROP 1 LAST PACK_TYPE C0805
J 0
(100 2200);
DISPLAY 0.638298 (100 2200);
FORCEPROP 1 LAST VALUE 47UF
J 0
(100 2450);
DISPLAY 0.638298 (100 2450);
FORCEPROP 1 LAST MATERIAL X6S
J 0
(100 2300);
DISPLAY 0.638298 (100 2300);
FORCEPROP 1 LAST $LOCATION C349
J 0
(100 2500);
DISPLAY 0.638298 (100 2500);
FORCEPROP 1 LASTPIN (50 2500) $PN 1
J 0
(60 2480);
DISPLAY 0.787234 (60 2480);
FORCEPROP 1 LASTPIN (50 2300) $PN 2
J 0
(60 2280);
DISPLAY 0.787234 (60 2280);
FORCEPROP 2 LAST CDS_LIB pure_quanta
J 0
(50 2400);
PAINT MONO (50 2400);
DISPLAY INVISIBLE (50 2400);
FORCEPROP 1 LAST $LOCATION C349
J 0
(100 2600);
DISPLAY 1.021277 (100 2600);
DISPLAY INVISIBLE (100 2600);
FORCEPROP 2 LAST CDS_LOCATION C349
J 0
(100 2600);
DISPLAY 1.021277 (100 2600);
DISPLAY INVISIBLE (100 2600);
FORCEPROP 2 LAST $SEC 1
J 0
(100 2600);
DISPLAY 0.680851 (100 2600);
PAINT MONO (100 2600);
DISPLAY INVISIBLE (100 2600);
FORCEPROP 2 LAST CDS_SEC 1
J 0
(100 2600);
DISPLAY 1.021277 (100 2600);
DISPLAY INVISIBLE (100 2600);
FORCEPROP 1 LAST PATH I63
J 0
(100 2550);
DISPLAY 0.978723 (100 2550);
PAINT WHITE (100 2550);
DISPLAY INVISIBLE (100 2550);
FORCEADD Q_CAP..1
(500 2400);
FORCEPROP 1 LAST PART_NUMBER CH647KMEA04
J 0
(550 2250);
DISPLAY 0.638298 (550 2250);
DISPLAY INVISIBLE (550 2250);
FORCEPROP 1 LAST TOLERANCE 20%
J 0
(550 2350);
DISPLAY 0.638298 (550 2350);
FORCEPROP 1 LAST VOLTAGE 4V
J 0
(550 2400);
DISPLAY 0.638298 (550 2400);
FORCEPROP 1 LAST PACK_TYPE C0805
J 0
(550 2200);
DISPLAY 0.638298 (550 2200);
FORCEPROP 1 LAST VALUE 47UF
J 0
(550 2450);
DISPLAY 0.638298 (550 2450);
FORCEPROP 1 LAST MATERIAL X6S
J 0
(550 2300);
DISPLAY 0.638298 (550 2300);
FORCEPROP 1 LAST $LOCATION C351
J 0
(550 2500);
DISPLAY 0.638298 (550 2500);
FORCEPROP 1 LASTPIN (500 2500) $PN 1
J 0
(510 2480);
DISPLAY 0.787234 (510 2480);
FORCEPROP 1 LASTPIN (500 2300) $PN 2
J 0
(510 2280);
DISPLAY 0.787234 (510 2280);
FORCEPROP 2 LAST CDS_LIB pure_quanta
J 0
(500 2400);
PAINT MONO (500 2400);
DISPLAY INVISIBLE (500 2400);
FORCEPROP 1 LAST $LOCATION C351
J 0
(550 2600);
DISPLAY 1.021277 (550 2600);
DISPLAY INVISIBLE (550 2600);
FORCEPROP 2 LAST CDS_LOCATION C351
J 0
(550 2600);
DISPLAY 1.021277 (550 2600);
DISPLAY INVISIBLE (550 2600);
FORCEPROP 2 LAST $SEC 1
J 0
(550 2600);
DISPLAY 0.680851 (550 2600);
PAINT MONO (550 2600);
DISPLAY INVISIBLE (550 2600);
FORCEPROP 2 LAST CDS_SEC 1
J 0
(550 2600);
DISPLAY 1.021277 (550 2600);
DISPLAY INVISIBLE (550 2600);
FORCEPROP 1 LAST PATH I64
J 0
(550 2550);
DISPLAY 0.978723 (550 2550);
PAINT WHITE (550 2550);
DISPLAY INVISIBLE (550 2550);
FORCEADD Q_CAP..1
(950 2400);
FORCEPROP 1 LAST PART_NUMBER CH647KMEA04
J 0
(1000 2250);
DISPLAY 0.638298 (1000 2250);
DISPLAY INVISIBLE (1000 2250);
FORCEPROP 1 LAST TOLERANCE 20%
J 0
(1000 2350);
DISPLAY 0.638298 (1000 2350);
FORCEPROP 1 LAST VOLTAGE 4V
J 0
(1000 2400);
DISPLAY 0.638298 (1000 2400);
FORCEPROP 1 LAST PACK_TYPE C0805
J 0
(1000 2200);
DISPLAY 0.638298 (1000 2200);
FORCEPROP 1 LAST VALUE 47UF
J 0
(1000 2450);
DISPLAY 0.638298 (1000 2450);
FORCEPROP 1 LAST MATERIAL X6S
J 0
(1000 2300);
DISPLAY 0.638298 (1000 2300);
FORCEPROP 1 LAST $LOCATION C353
J 0
(1000 2500);
DISPLAY 0.638298 (1000 2500);
FORCEPROP 1 LASTPIN (950 2500) $PN 1
J 0
(960 2480);
DISPLAY 0.787234 (960 2480);
FORCEPROP 1 LASTPIN (950 2300) $PN 2
J 0
(960 2280);
DISPLAY 0.787234 (960 2280);
FORCEPROP 2 LAST CDS_LIB pure_quanta
J 0
(950 2400);
PAINT MONO (950 2400);
DISPLAY INVISIBLE (950 2400);
FORCEPROP 1 LAST $LOCATION C353
J 0
(1000 2600);
DISPLAY 1.021277 (1000 2600);
DISPLAY INVISIBLE (1000 2600);
FORCEPROP 2 LAST CDS_LOCATION C353
J 0
(1000 2600);
DISPLAY 1.021277 (1000 2600);
DISPLAY INVISIBLE (1000 2600);
FORCEPROP 2 LAST $SEC 1
J 0
(1000 2600);
DISPLAY 0.680851 (1000 2600);
PAINT MONO (1000 2600);
DISPLAY INVISIBLE (1000 2600);
FORCEPROP 2 LAST CDS_SEC 1
J 0
(1000 2600);
DISPLAY 1.021277 (1000 2600);
DISPLAY INVISIBLE (1000 2600);
FORCEPROP 1 LAST PATH I65
J 0
(1000 2550);
DISPLAY 0.978723 (1000 2550);
PAINT WHITE (1000 2550);
DISPLAY INVISIBLE (1000 2550);
FORCEADD Q_CAP..1
(1825 2400);
FORCEPROP 1 LAST PART_NUMBER CH647KMEA04
J 0
(1875 2250);
DISPLAY 0.638298 (1875 2250);
DISPLAY INVISIBLE (1875 2250);
FORCEPROP 1 LAST VALUE 47UF
J 0
(1875 2450);
DISPLAY 0.638298 (1875 2450);
FORCEPROP 1 LAST VOLTAGE 4V
J 0
(1875 2400);
DISPLAY 0.638298 (1875 2400);
FORCEPROP 1 LAST PACK_TYPE C0805
J 0
(1875 2200);
DISPLAY 0.638298 (1875 2200);
FORCEPROP 1 LAST TOLERANCE 20%
J 0
(1875 2350);
DISPLAY 0.638298 (1875 2350);
FORCEPROP 1 LAST MATERIAL X6S
J 0
(1875 2300);
DISPLAY 0.638298 (1875 2300);
FORCEPROP 1 LAST $LOCATION C337
J 0
(1875 2500);
DISPLAY 0.787234 (1875 2500);
FORCEPROP 1 LASTPIN (1825 2500) $PN 1
J 0
(1835 2480);
DISPLAY 0.787234 (1835 2480);
PAINT MONO (1835 2480);
FORCEPROP 1 LASTPIN (1825 2300) $PN 2
J 0
(1835 2280);
DISPLAY 0.787234 (1835 2280);
PAINT MONO (1835 2280);
FORCEPROP 2 LAST CDS_LIB pure_quanta
J 0
(1825 2400);
DISPLAY INVISIBLE (1825 2400);
FORCEPROP 2 LAST CDS_LOCATION C337
J 0
(1875 2600);
DISPLAY 1.021277 (1875 2600);
DISPLAY INVISIBLE (1875 2600);
FORCEPROP 0 LAST $SEC 1
J 0
(1875 2550);
DISPLAY 0.680851 (1875 2550);
PAINT MONO (1875 2550);
DISPLAY INVISIBLE (1875 2550);
FORCEPROP 2 LAST CDS_SEC 1
J 0
(1875 2600);
DISPLAY 1.021277 (1875 2600);
DISPLAY INVISIBLE (1875 2600);
FORCEPROP 1 LAST PATH I66
J 0
(1875 2550);
DISPLAY 0.978723 (1875 2550);
PAINT WHITE (1875 2550);
DISPLAY INVISIBLE (1875 2550);
FORCEADD UNIVERSAL_POWER..1
(1825 2675);
FORCEPROP 3 LASTPIN (1825 2625) SIG_NAME PVCCIN_CPU1\g
J 0
(1835 2635);
DISPLAY 0.659574 (1835 2635);
PAINT MONO (1835 2635);
DISPLAY INVISIBLE (1835 2635);
FORCEPROP 1 LAST HDL_POWER PVCCIN_CPU1
J 1
(2025 2725);
DISPLAY 0.872340 (2025 2725);
PAINT GREEN (2025 2725);
FORCEPROP 2 LAST CDS_LIB logical_power
J 0
(1825 2675);
PAINT MONO (1825 2675);
DISPLAY INVISIBLE (1825 2675);
FORCEPROP 1 LAST PATH I67
J 0
(1875 2700);
DISPLAY 0.872340 (1875 2700);
PAINT AQUA (1875 2700);
DISPLAY INVISIBLE (1875 2700);
FORCEADD Q_CAP..1
(2275 2400);
FORCEPROP 1 LAST PART_NUMBER CH647KMEA04
J 0
(2325 2250);
DISPLAY 0.638298 (2325 2250);
DISPLAY INVISIBLE (2325 2250);
FORCEPROP 1 LAST VOLTAGE 4V
J 0
(2325 2400);
DISPLAY 0.638298 (2325 2400);
FORCEPROP 1 LAST VALUE 47UF
J 0
(2325 2450);
DISPLAY 0.638298 (2325 2450);
FORCEPROP 1 LAST PACK_TYPE C0805
J 0
(2325 2200);
DISPLAY 0.638298 (2325 2200);
FORCEPROP 1 LAST MATERIAL X6S
J 0
(2325 2300);
DISPLAY 0.638298 (2325 2300);
FORCEPROP 1 LAST TOLERANCE 20%
J 0
(2325 2350);
DISPLAY 0.638298 (2325 2350);
FORCEPROP 1 LAST $LOCATION C483
J 0
(2325 2500);
DISPLAY 0.787234 (2325 2500);
FORCEPROP 1 LASTPIN (2275 2500) $PN 1
J 0
(2285 2480);
DISPLAY 0.787234 (2285 2480);
PAINT MONO (2285 2480);
FORCEPROP 1 LASTPIN (2275 2300) $PN 2
J 0
(2285 2280);
DISPLAY 0.787234 (2285 2280);
PAINT MONO (2285 2280);
FORCEPROP 2 LAST CDS_LIB pure_quanta
J 0
(2275 2400);
DISPLAY INVISIBLE (2275 2400);
FORCEPROP 2 LAST CDS_LOCATION C483
J 0
(2325 2600);
DISPLAY 1.021277 (2325 2600);
DISPLAY INVISIBLE (2325 2600);
FORCEPROP 0 LAST $SEC 1
J 0
(2325 2550);
DISPLAY 0.680851 (2325 2550);
PAINT MONO (2325 2550);
DISPLAY INVISIBLE (2325 2550);
FORCEPROP 2 LAST CDS_SEC 1
J 0
(2325 2600);
DISPLAY 1.021277 (2325 2600);
DISPLAY INVISIBLE (2325 2600);
FORCEPROP 1 LAST PATH I68
J 0
(2325 2550);
DISPLAY 0.978723 (2325 2550);
PAINT WHITE (2325 2550);
DISPLAY INVISIBLE (2325 2550);
FORCEADD Q_CAP..1
(-2650 -2200);
FORCEPROP 1 LAST PART_NUMBER CH647LME900
J 0
(-2600 -2350);
DISPLAY 0.638298 (-2600 -2350);
DISPLAY INVISIBLE (-2600 -2350);
FORCEPROP 1 LAST TOLERANCE 20%
J 0
(-2600 -2250);
DISPLAY 0.638298 (-2600 -2250);
FORCEPROP 1 LAST MATERIAL X6S
J 0
(-2600 -2300);
DISPLAY 0.638298 (-2600 -2300);
FORCEPROP 1 LAST VOLTAGE 2.5V
J 0
(-2600 -2200);
DISPLAY 0.638298 (-2600 -2200);
FORCEPROP 1 LAST PACK_TYPE C0603
J 0
(-2600 -2400);
DISPLAY 0.638298 (-2600 -2400);
FORCEPROP 1 LAST VALUE 47UF
J 0
(-2600 -2150);
DISPLAY 0.638298 (-2600 -2150);
FORCEPROP 1 LAST $LOCATION C465
J 0
(-2600 -2100);
DISPLAY 0.978723 (-2600 -2100);
FORCEPROP 1 LASTPIN (-2650 -2100) $PN 1
J 0
(-2640 -2120);
DISPLAY 0.787234 (-2640 -2120);
FORCEPROP 1 LASTPIN (-2650 -2300) $PN 2
J 0
(-2640 -2320);
DISPLAY 0.787234 (-2640 -2320);
FORCEPROP 2 LAST CDS_LIB pure_quanta
J 0
(-2650 -2200);
PAINT MONO (-2650 -2200);
DISPLAY INVISIBLE (-2650 -2200);
FORCEPROP 2 LAST CDS_LOCATION C465
J 0
(-2600 -2000);
DISPLAY 1.021277 (-2600 -2000);
DISPLAY INVISIBLE (-2600 -2000);
FORCEPROP 2 LAST $SEC 1
J 0
(-2600 -2000);
DISPLAY 0.680851 (-2600 -2000);
PAINT MONO (-2600 -2000);
DISPLAY INVISIBLE (-2600 -2000);
FORCEPROP 2 LAST CDS_SEC 1
J 0
(-2600 -2000);
DISPLAY 1.021277 (-2600 -2000);
DISPLAY INVISIBLE (-2600 -2000);
FORCEPROP 1 LAST PATH I7
J 0
(-2600 -2050);
DISPLAY 0.978723 (-2600 -2050);
PAINT WHITE (-2600 -2050);
DISPLAY INVISIBLE (-2600 -2050);
FORCEADD Q_CAP..1
(-4450 -1250);
FORCEPROP 1 LAST PART_NUMBER CH647KMEA04
J 0
(-4400 -1400);
DISPLAY 0.638298 (-4400 -1400);
DISPLAY INVISIBLE (-4400 -1400);
FORCEPROP 1 LAST PACK_TYPE C0805
J 0
(-4400 -1450);
DISPLAY 0.638298 (-4400 -1450);
FORCEPROP 1 LAST VALUE 47UF
J 0
(-4400 -1200);
DISPLAY 0.638298 (-4400 -1200);
FORCEPROP 1 LAST TOLERANCE 20%
J 0
(-4400 -1300);
DISPLAY 0.638298 (-4400 -1300);
FORCEPROP 1 LAST MATERIAL X6S
J 0
(-4400 -1350);
DISPLAY 0.638298 (-4400 -1350);
FORCEPROP 1 LAST VOLTAGE 4V
J 0
(-4400 -1250);
DISPLAY 0.638298 (-4400 -1250);
FORCEPROP 1 LAST $LOCATION C478
J 0
(-4400 -1150);
DISPLAY 0.978723 (-4400 -1150);
FORCEPROP 1 LASTPIN (-4450 -1150) $PN 1
J 0
(-4440 -1170);
DISPLAY 0.787234 (-4440 -1170);
FORCEPROP 1 LASTPIN (-4450 -1350) $PN 2
J 0
(-4440 -1370);
DISPLAY 0.787234 (-4440 -1370);
FORCEPROP 2 LAST CDS_LIB pure_quanta
J 0
(-4450 -1250);
PAINT MONO (-4450 -1250);
DISPLAY INVISIBLE (-4450 -1250);
FORCEPROP 2 LAST CDS_LOCATION C478
J 0
(-4400 -1050);
DISPLAY 1.021277 (-4400 -1050);
DISPLAY INVISIBLE (-4400 -1050);
FORCEPROP 2 LAST $SEC 1
J 0
(-4400 -1050);
DISPLAY 0.680851 (-4400 -1050);
PAINT MONO (-4400 -1050);
DISPLAY INVISIBLE (-4400 -1050);
FORCEPROP 2 LAST CDS_SEC 1
J 0
(-4400 -1050);
DISPLAY 1.021277 (-4400 -1050);
DISPLAY INVISIBLE (-4400 -1050);
FORCEPROP 1 LAST PATH I8
J 0
(-4400 -1100);
DISPLAY 0.978723 (-4400 -1100);
PAINT WHITE (-4400 -1100);
DISPLAY INVISIBLE (-4400 -1100);
FORCEADD UNIVERSAL_POWER..1
(-4450 -975);
FORCEPROP 3 LASTPIN (-4450 -1025) SIG_NAME PVCCINFAON_CPU1\g
J 0
(-4440 -1015);
DISPLAY 0.659574 (-4440 -1015);
PAINT MONO (-4440 -1015);
DISPLAY INVISIBLE (-4440 -1015);
FORCEPROP 1 LAST HDL_POWER PVCCINFAON_CPU1
J 1
(-4175 -925);
DISPLAY 0.872340 (-4175 -925);
PAINT GREEN (-4175 -925);
FORCEPROP 2 LAST CDS_LIB logical_power
J 0
(-4450 -975);
PAINT MONO (-4450 -975);
DISPLAY INVISIBLE (-4450 -975);
FORCEPROP 1 LAST PATH I9
J 0
(-4400 -950);
DISPLAY 0.872340 (-4400 -950);
PAINT AQUA (-4400 -950);
DISPLAY INVISIBLE (-4400 -950);
FORCEADD QUANTA_TITLE_BLOCK_C..1
(4650 -3400);
FORCEPROP 0 LAST CDS_CON_LAST_MODIFIED Fri Aug 25 14:00:58 2023
J 0
(2765 -3385);
PAINT MONO (2765 -3385);
DISPLAY INVISIBLE (2765 -3385);
FORCEPROP 2 LAST CUSTOM_TXT_CDS <XR_PAGE_TITLE>
J 0
(-3240 1850);
DISPLAY 0.638298 (-3240 1850);
PAINT PINK (-3240 1850);
DISPLAY INVISIBLE (-3240 1850);
FORCEPROP 2 LAST CUSTOM_TXT_CDS <Q_NUMBER>
J 0
(3247 -3297);
DISPLAY 1.212766 (3247 -3297);
FORCEPROP 2 LAST CUSTOM_TXT_CDS <CON_LAST_MODIFIED>
J 0
(2800 -3400);
DISPLAY 0.978723 (2800 -3400);
FORCEPROP 1 LAST CUSTOM_TXT_CDS <NAME_2>
J 0
(1475 -3350);
FORCEPROP 1 LAST CUSTOM_TXT_CDS <NAME_1>
J 0
(1475 -3225);
FORCEPROP 1 LAST CUSTOM_TXT_CDS <Q_PROJ>
J 0
(2268 -3298);
DISPLAY 1.212766 (2268 -3298);
FORCEPROP 1 LAST CUSTOM_TXT_CDS <Q_REV>
J 0
(4466 -3297);
DISPLAY 1.212766 (4466 -3297);
FORCEPROP 1 LAST CUSTOM_TXT_CDS <CON_PAGE_NUM> OF <CON_TOTAL_PAGES>
J 0
(4204 -3382);
DISPLAY 0.978723 (4204 -3382);
FORCEPROP 1 LAST Q_TITLE SPR CPU1 BOTTOM DECOUPLING CAPS
J 0
(-4691 -3374);
DISPLAY 1.957447 (-4691 -3374);
PAINT GREEN (-4691 -3374);
FORCEPROP 1 LAST Q_DEPT 
J 1
(887 -3351);
DISPLAY 1.957447 (887 -3351);
PAINT GREEN (887 -3351);
FORCEPROP 1 LAST COMMENT_BODY TRUE
J 0
(4662 -3413);
DISPLAY 0.978723 (4662 -3413);
PAINT GREEN (4662 -3413);
DISPLAY INVISIBLE (4662 -3413);
FORCEPROP 2 LAST CDS_XR_PAGE_TITLE CR-78 : @S9S_MB_2U_LIB.S9S_MB_2U(SCH_1):PAGE78
J 0
(-3240 1850);
DISPLAY 0.638298 (-3240 1850);
PAINT PINK (-3240 1850);
DISPLAY INVISIBLE (-3240 1850);
FORCEPROP 2 LAST CDS_LIB pure_quanta
J 0
(4650 -3400);
PAINT MONO (4650 -3400);
DISPLAY INVISIBLE (4650 -3400);
FORCEPROP 1 LAST CDS_LMAN_SYM_OUTLINE -9475,6775,100,-125
J 0
(4650 -3400);
DISPLAY 0.468085 (4650 -3400);
PAINT GREEN (4650 -3400);
DISPLAY INVISIBLE (4650 -3400);
FORCEPROP 2 LAST PAGE_BORDER TRUE
J 0
(-3240 1850);
DISPLAY 0.638298 (-3240 1850);
PAINT PINK (-3240 1850);
DISPLAY INVISIBLE (-3240 1850);
WIRE 16 -1 (-4450 -50)(-4450 0);
WIRE 16 -1 (-4000 -50)(-4450 -50);
WIRE 16 -1 (-4450 -50)(-4450 -125);
WIRE 16 -1 (-4450 -2025)(-4450 -1975);
WIRE 16 -1 (-4000 -2025)(-4450 -2025);
WIRE 16 -1 (-4450 -2025)(-4450 -2100);
WIRE 16 -1 (-4450 -1075)(-4450 -1025);
WIRE 16 -1 (-4000 -1075)(-4450 -1075);
WIRE 16 -1 (-4450 -1075)(-4450 -1150);
WIRE 16 -1 (-4450 850)(-4450 900);
WIRE 16 -1 (-4000 850)(-4450 850);
WIRE 16 -1 (-4450 850)(-4450 775);
WIRE 16 -1 (-4450 1800)(-4450 1850);
WIRE 16 -1 (-4000 1800)(-4450 1800);
WIRE 16 -1 (-4450 1800)(-4450 1725);
WIRE 16 -1 (-4450 2575)(-4450 2625);
WIRE 16 -1 (-4000 2575)(-4450 2575);
WIRE 16 -1 (-4450 2575)(-4450 2500);
WIRE 16 -1 (-100 -1075)(-100 -1025);
WIRE 16 -1 (350 -1075)(-100 -1075);
WIRE 16 -1 (-100 -1075)(-100 -1150);
WIRE 16 -1 (-100 -50)(-100 0);
WIRE 16 -1 (350 -50)(-100 -50);
WIRE 16 -1 (-100 -50)(-100 -125);
WIRE 16 -1 (1825 2575)(1825 2625);
WIRE 16 -1 (2275 2575)(1825 2575);
WIRE 16 -1 (1825 2575)(1825 2500);
WIRE 16 -1 (-2650 -2500)(-2650 -2425);
WIRE 16 -1 (-4000 -525)(-4000 -450);
WIRE 16 -1 (-3100 -1550)(-3100 -1475);
WIRE 16 -1 (-3100 400)(-3100 450);
WIRE 16 -1 (1250 -1550)(1250 -1475);
WIRE 16 -1 (1250 -525)(1250 -450);
WIRE 16 -1 (500 1325)(500 1400);
WIRE 16 -1 (950 2100)(950 2175);
WIRE 16 -1 (2275 2100)(2275 2175);
WIRE 16 -1 (-100 -1475)(-100 -1350);
WIRE 16 -1 (350 -1475)(-100 -1475);
WIRE 16 -1 (350 -1475)(350 -1350);
WIRE 16 -1 (800 -1475)(350 -1475);
WIRE 16 -1 (800 -1475)(800 -1350);
WIRE 16 -1 (1250 -1475)(800 -1475);
WIRE 16 -1 (1250 -1475)(1250 -1350);
WIRE 16 -1 (-4450 -2425)(-4450 -2300);
WIRE 16 -1 (-4000 -2425)(-4450 -2425);
WIRE 16 -1 (-4000 -2425)(-4000 -2300);
WIRE 16 -1 (-3550 -2425)(-4000 -2425);
WIRE 16 -1 (-3550 -2425)(-3550 -2300);
WIRE 16 -1 (-3100 -2425)(-3550 -2425);
WIRE 16 -1 (-3100 -2425)(-3100 -2300);
WIRE 16 -1 (-2650 -2425)(-2650 -2300);
WIRE 16 -1 (-2650 -2425)(-3100 -2425);
WIRE 16 -1 (-4000 -2100)(-4000 -2025);
WIRE 16 -1 (-3550 -2025)(-3550 -2100);
WIRE 16 -1 (-3550 -2025)(-4000 -2025);
WIRE 16 -1 (-3100 -2100)(-3100 -2025);
WIRE 16 -1 (-3100 -2025)(-3550 -2025);
WIRE 16 -1 (-2650 -2025)(-3100 -2025);
WIRE 16 -1 (-2650 -2100)(-2650 -2025);
WIRE 16 -1 (-4450 -1475)(-4450 -1350);
WIRE 16 -1 (-4000 -1475)(-4450 -1475);
WIRE 16 -1 (-4000 -1475)(-4000 -1350);
WIRE 16 -1 (-3550 -1475)(-4000 -1475);
WIRE 16 -1 (-3550 -1475)(-3550 -1350);
WIRE 16 -1 (-3100 -1475)(-3550 -1475);
WIRE 16 -1 (-3100 -1475)(-3100 -1350);
WIRE 16 -1 (2275 2500)(2275 2575);
WIRE 16 -1 (-4000 2500)(-4000 2575);
WIRE 16 -1 (-3550 2575)(-4000 2575);
WIRE 16 -1 (-3550 2575)(-3550 2500);
WIRE 16 -1 (-3100 2500)(-3100 2575);
WIRE 16 -1 (-3100 2575)(-3550 2575);
WIRE 16 -1 (-2650 2575)(-3100 2575);
WIRE 16 -1 (-2650 2500)(-2650 2575);
WIRE 16 -1 (-2200 2575)(-2650 2575);
WIRE 16 -1 (-2200 2575)(-2200 2500);
WIRE 16 -1 (-1750 2575)(-2200 2575);
WIRE 16 -1 (-1750 2500)(-1750 2575);
WIRE 16 -1 (-1300 2575)(-1750 2575);
WIRE 16 -1 (-1300 2500)(-1300 2575);
WIRE 16 -1 (-850 2575)(-1300 2575);
WIRE 16 -1 (-850 2575)(-850 2500);
WIRE 16 -1 (-400 2575)(-850 2575);
WIRE 16 -1 (-400 2500)(-400 2575);
WIRE 16 -1 (50 2575)(-400 2575);
WIRE 16 -1 (50 2500)(50 2575);
WIRE 16 -1 (500 2575)(500 2500);
WIRE 16 -1 (500 2575)(50 2575);
WIRE 16 -1 (950 2575)(500 2575);
WIRE 16 -1 (950 2500)(950 2575);
WIRE 16 -1 (1825 2175)(1825 2300);
WIRE 16 -1 (2275 2175)(1825 2175);
WIRE 16 -1 (2275 2175)(2275 2300);
WIRE 16 -1 (-4450 2175)(-4450 2300);
WIRE 16 -1 (-4000 2175)(-4450 2175);
WIRE 16 -1 (-4000 2175)(-4000 2300);
WIRE 16 -1 (-3550 2175)(-4000 2175);
WIRE 16 -1 (-3550 2175)(-3550 2300);
WIRE 16 -1 (-3100 2175)(-3550 2175);
WIRE 16 -1 (-3100 2175)(-3100 2300);
WIRE 16 -1 (-2650 2175)(-3100 2175);
WIRE 16 -1 (-2650 2175)(-2650 2300);
WIRE 16 -1 (-2200 2175)(-2650 2175);
WIRE 16 -1 (-2200 2175)(-2200 2300);
WIRE 16 -1 (-1750 2175)(-2200 2175);
WIRE 16 -1 (-1750 2175)(-1750 2300);
WIRE 16 -1 (-1300 2175)(-1750 2175);
WIRE 16 -1 (-1300 2175)(-1300 2300);
WIRE 16 -1 (-850 2175)(-1300 2175);
WIRE 16 -1 (-850 2175)(-850 2300);
WIRE 16 -1 (-400 2175)(-850 2175);
WIRE 16 -1 (-400 2175)(-400 2300);
WIRE 16 -1 (50 2175)(-400 2175);
WIRE 16 -1 (50 2175)(50 2300);
WIRE 16 -1 (500 2175)(50 2175);
WIRE 16 -1 (500 2175)(500 2300);
WIRE 16 -1 (950 2175)(500 2175);
WIRE 16 -1 (950 2175)(950 2300);
WIRE 16 -1 (-4000 1725)(-4000 1800);
WIRE 16 -1 (-3550 1800)(-4000 1800);
WIRE 16 -1 (-3550 1800)(-3550 1725);
WIRE 16 -1 (-3100 1800)(-3550 1800);
WIRE 16 -1 (-3100 1725)(-3100 1800);
WIRE 16 -1 (-2650 1800)(-3100 1800);
WIRE 16 -1 (-2650 1725)(-2650 1800);
WIRE 16 -1 (-2200 1800)(-2650 1800);
WIRE 16 -1 (-2200 1800)(-2200 1725);
WIRE 16 -1 (-1750 1800)(-2200 1800);
WIRE 16 -1 (-1750 1725)(-1750 1800);
WIRE 16 -1 (-1300 1800)(-1750 1800);
WIRE 16 -1 (-1300 1725)(-1300 1800);
WIRE 16 -1 (-850 1800)(-1300 1800);
WIRE 16 -1 (-850 1800)(-850 1725);
WIRE 16 -1 (-400 1800)(-850 1800);
WIRE 16 -1 (-400 1725)(-400 1800);
WIRE 16 -1 (50 1800)(-400 1800);
WIRE 16 -1 (50 1800)(50 1725);
WIRE 16 -1 (500 1800)(50 1800);
WIRE 16 -1 (500 1725)(500 1800);
WIRE 16 -1 (-4450 1400)(-4450 1525);
WIRE 16 -1 (-4000 1400)(-4450 1400);
WIRE 16 -1 (-4000 1400)(-4000 1525);
WIRE 16 -1 (-3550 1400)(-4000 1400);
WIRE 16 -1 (-3550 1400)(-3550 1525);
WIRE 16 -1 (-3100 1400)(-3550 1400);
WIRE 16 -1 (-3100 1400)(-3100 1525);
WIRE 16 -1 (-2650 1400)(-3100 1400);
WIRE 16 -1 (-2650 1400)(-2650 1525);
WIRE 16 -1 (-2200 1400)(-2650 1400);
WIRE 16 -1 (-2200 1400)(-2200 1525);
WIRE 16 -1 (-1750 1400)(-2200 1400);
WIRE 16 -1 (-1750 1400)(-1750 1525);
WIRE 16 -1 (-1300 1400)(-1750 1400);
WIRE 16 -1 (-1300 1400)(-1300 1525);
WIRE 16 -1 (-850 1400)(-1300 1400);
WIRE 16 -1 (-850 1400)(-850 1525);
WIRE 16 -1 (-400 1400)(-850 1400);
WIRE 16 -1 (-400 1400)(-400 1525);
WIRE 16 -1 (50 1400)(-400 1400);
WIRE 16 -1 (50 1400)(50 1525);
WIRE 16 -1 (500 1400)(50 1400);
WIRE 16 -1 (500 1400)(500 1525);
WIRE 16 -1 (350 -125)(350 -50);
WIRE 16 -1 (350 -50)(800 -50);
WIRE 16 -1 (800 -50)(800 -125);
WIRE 16 -1 (1250 -50)(800 -50);
WIRE 16 -1 (1250 -125)(1250 -50);
WIRE 16 -1 (-100 -450)(-100 -325);
WIRE 16 -1 (350 -450)(-100 -450);
WIRE 16 -1 (350 -450)(350 -325);
WIRE 16 -1 (800 -450)(350 -450);
WIRE 16 -1 (800 -450)(800 -325);
WIRE 16 -1 (1250 -450)(800 -450);
WIRE 16 -1 (1250 -450)(1250 -325);
WIRE 16 -1 (350 -1150)(350 -1075);
WIRE 16 -1 (800 -1075)(350 -1075);
WIRE 16 -1 (800 -1075)(800 -1150);
WIRE 16 -1 (1250 -1075)(800 -1075);
WIRE 16 -1 (1250 -1075)(1250 -1150);
WIRE 16 -1 (-4000 775)(-4000 850);
WIRE 16 -1 (-3550 850)(-4000 850);
WIRE 16 -1 (-3550 775)(-3550 850);
WIRE 16 -1 (-3100 850)(-3550 850);
WIRE 16 -1 (-3100 775)(-3100 850);
WIRE 16 -1 (-4450 450)(-4450 575);
WIRE 16 -1 (-3100 575)(-3100 450);
WIRE 16 -1 (-4000 450)(-4450 450);
WIRE 16 -1 (-4000 450)(-4000 575);
WIRE 16 -1 (-3550 450)(-4000 450);
WIRE 16 -1 (-3100 450)(-3550 450);
WIRE 16 -1 (-3550 575)(-3550 450);
WIRE 16 -1 (-4000 -1150)(-4000 -1075);
WIRE 16 -1 (-3550 -1075)(-4000 -1075);
WIRE 16 -1 (-3550 -1150)(-3550 -1075);
WIRE 16 -1 (-3100 -1075)(-3550 -1075);
WIRE 16 -1 (-3100 -1150)(-3100 -1075);
WIRE 16 -1 (-4000 -125)(-4000 -50);
WIRE 16 -1 (-4450 -450)(-4450 -325);
WIRE 16 -1 (-4000 -450)(-4450 -450);
WIRE 16 -1 (-4000 -450)(-4000 -325);
DOT 1 (1825 2575);
DOT 1 (500 2575);
DOT 1 (50 2575);
DOT 1 (2275 2175);
DOT 1 (950 2175);
DOT 1 (500 2175);
DOT 1 (500 1400);
DOT 1 (50 2175);
DOT 1 (50 1800);
DOT 1 (50 1400);
DOT 1 (800 -50);
DOT 1 (1250 -450);
DOT 1 (800 -450);
DOT 1 (800 -1075);
DOT 1 (1250 -1475);
DOT 1 (800 -1475);
DOT 1 (350 -50);
DOT 1 (350 -450);
DOT 1 (-100 -50);
DOT 1 (350 -1075);
DOT 1 (350 -1475);
DOT 1 (-100 -1075);
DOT 1 (-400 2575);
DOT 1 (-850 2575);
DOT 1 (-1300 2575);
DOT 1 (-1750 2575);
DOT 1 (-2200 2575);
DOT 1 (-2650 2575);
DOT 1 (-3100 2575);
DOT 1 (-3550 2575);
DOT 1 (-4000 2575);
DOT 1 (-400 2175);
DOT 1 (-400 1800);
DOT 1 (-400 1400);
DOT 1 (-850 2175);
DOT 1 (-850 1800);
DOT 1 (-850 1400);
DOT 1 (-1300 2175);
DOT 1 (-1300 1800);
DOT 1 (-1750 2175);
DOT 1 (-1750 1800);
DOT 1 (-1300 1400);
DOT 1 (-1750 1400);
DOT 1 (-2200 2175);
DOT 1 (-2200 1800);
DOT 1 (-2200 1400);
DOT 1 (-2650 2175);
DOT 1 (-2650 1800);
DOT 1 (-2650 1400);
DOT 1 (-3100 2175);
DOT 1 (-3100 1800);
DOT 1 (-3100 1400);
DOT 1 (-3100 450);
DOT 1 (-3550 2175);
DOT 1 (-3550 1800);
DOT 1 (-3550 1400);
DOT 1 (-4000 2175);
DOT 1 (-4000 1800);
DOT 1 (-4000 1400);
DOT 1 (-3550 850);
DOT 1 (-3550 450);
DOT 1 (-4000 850);
DOT 1 (-4000 450);
DOT 1 (-3100 -1475);
DOT 1 (-4000 -450);
DOT 1 (-3550 -1075);
DOT 1 (-3550 -1475);
DOT 1 (-4000 -1075);
DOT 1 (-4000 -1475);
DOT 1 (-4450 2575);
DOT 1 (-4450 1800);
DOT 1 (-4450 850);
DOT 1 (-4450 -50);
DOT 1 (-4450 -1075);
DOT 1 (-2650 -2425);
DOT 1 (-3100 -2025);
DOT 1 (-3100 -2425);
DOT 1 (-3550 -2025);
DOT 1 (-3550 -2425);
DOT 1 (-4000 -2025);
DOT 1 (-4000 -2425);
DOT 1 (-4450 -2025);
FORCENOTE
PVCCFA_EHV: 2 100UF CAPS PLACED AT CAVITY(LEFT)
(-3771 -4) 0;
DISPLAY LEFT (-3771 -4);
DISPLAY 0.808511 (-3771 -4);
PAINT SKYBLUE (-3771 -4);
FORCENOTE
PVCCFA_EHV_FIVRA: 2 100UF CAPS ARE PLACED AT CAVITY(RIGHT)
(-3525 -1950) 0;
DISPLAY LEFT (-3525 -1950);
DISPLAY 0.808511 (-3525 -1950);
PAINT SKYBLUE (-3525 -1950);
FORCENOTE
PVCCFA_EHV_FIVRA: 2 100UF CAP & 1 47UF CAP ARE PLACED AT CAVITY(LEFT)
(-3525 -1875) 0;
DISPLAY LEFT (-3525 -1875);
DISPLAY 0.808511 (-3525 -1875);
PAINT SKYBLUE (-3525 -1875);
FORCENOTE
PVCCIN: 1 0805 47UF CAPS PLACED AT CAVITY(LEFT)
(2325 2725) 0;
DISPLAY LEFT (2325 2725);
DISPLAY 0.808511 (2325 2725);
PAINT SKYBLUE (2325 2725);
FORCENOTE
PVCCIN: 1 0805 47UF CAPS PLACED AT CAVITY(RIGHT)
(2325 2625) 0;
DISPLAY LEFT (2325 2625);
DISPLAY 0.808511 (2325 2625);
PAINT SKYBLUE (2325 2625);
FORCENOTE
PVNN_MAIN: 4 CAPS PLACED AT CAVITY(RIGHT)
(450 0) 0;
DISPLAY LEFT (450 0);
DISPLAY 0.808511 (450 0);
PAINT SKYBLUE (450 0);
FORCENOTE
PVCCIN: 13 0805 100UF CAPS PLACED AT CAVITY(LEFT)
(-3550 2650) 0;
DISPLAY LEFT (-3550 2650);
DISPLAY 0.808511 (-3550 2650);
PAINT SKYBLUE (-3550 2650);
FORCENOTE
PVCCD_HV: 1 100UF CAP & 1 47UF CAP ARE PLACED AT CAVITY(RIGHT)
(-3775 925) 0;
DISPLAY LEFT (-3775 925);
DISPLAY 0.808511 (-3775 925);
PAINT SKYBLUE (-3775 925);
FORCENOTE
PVCCD_HV: 1 100UF CAP & 1 47UF CAP ARE PLACED AT CAVITY(LEFT)
(-3775 1000) 0;
DISPLAY LEFT (-3775 1000);
DISPLAY 0.808511 (-3775 1000);
PAINT SKYBLUE (-3775 1000);
FORCENOTE
PVCCIN: 12 0805 100UF CAPS PLACED AT CAVITY(RIGHT)
(-3550 1925) 0;
DISPLAY LEFT (-3550 1925);
DISPLAY 0.808511 (-3550 1925);
PAINT SKYBLUE (-3550 1925);
FORCENOTE
PVNNINFAON: 4 CAPS PLACED AT CAVITY(LEFT)
(-3775 -1000) 0;
DISPLAY LEFT (-3775 -1000);
DISPLAY 0.808511 (-3775 -1000);
PAINT SKYBLUE (-3775 -1000);
QUIT
